FILE_TYPE = MACRO_DRAWING;
SET COLOR_WIRE YELLOW;
SET COLOR_PROP ORANGE;
SET COLOR_DOT WHITE;
SET COLOR_ARC YELLOW;
SET COLOR_BODY GREEN;
SET COLOR_NOTE PURPLE;
SET PROP_DISPLAY VALUE;
SET PAGE_NUMBER P83;
FORCEADD UNIVERSAL_GND..1
(-1425 -175);
FORCEPROP 3 LASTPIN (-1425 -125) SIG_NAME GND\g
J 0
(-1415 -115);
DISPLAY 0.659574 (-1415 -115);
PAINT MONO (-1415 -115);
DISPLAY INVISIBLE (-1415 -115);
FORCEPROP 2 LAST CDS_LIB logical_power
J 0
(-1425 -175);
PAINT MONO (-1425 -175);
DISPLAY INVISIBLE (-1425 -175);
FORCEPROP 1 LAST HDL_POWER GND
J 1
(-1400 -250);
DISPLAY 0.872340 (-1400 -250);
PAINT GREEN (-1400 -250);
DISPLAY INVISIBLE (-1400 -250);
FORCEPROP 1 LAST PATH I1
J 0
(-1350 -175);
DISPLAY 0.872340 (-1350 -175);
PAINT AQUA (-1350 -175);
DISPLAY INVISIBLE (-1350 -175);
FORCEADD Q_RES..2
(-1425 50);
FORCEPROP 1 LAST PART_NUMBER CS31542FB02
J 0
(-1385 -75);
DISPLAY 0.978723 (-1385 -75);
DISPLAY INVISIBLE (-1385 -75);
FORCEPROP 1 LAST PACK_TYPE 0402LF
J 0
(-1385 -125);
DISPLAY 0.978723 (-1385 -125);
FORCEPROP 1 LAST MATERIAL CHIP
J 0
(-1385 -25);
DISPLAY 0.978723 (-1385 -25);
FORCEPROP 1 LAST TOLERANCE 1%
J 0
(-1380 75);
DISPLAY 0.978723 (-1380 75);
FORCEPROP 1 LAST VALUE 15.4K
J 0
(-1380 125);
DISPLAY 0.978723 (-1380 125);
FORCEPROP 1 LAST WATTAGE 1/16W
J 0
(-1385 25);
DISPLAY 0.978723 (-1385 25);
FORCEPROP 1 LAST $LOCATION R27
J 0
(-1380 175);
DISPLAY 1.234043 (-1380 175);
FORCEPROP 1 LASTPIN (-1425 150) $PN 1
J 0
(-1420 112);
DISPLAY 0.787234 (-1420 112);
PAINT MONO (-1420 112);
FORCEPROP 1 LASTPIN (-1425 -50) $PN 2
J 0
(-1420 -40);
DISPLAY 0.787234 (-1420 -40);
PAINT MONO (-1420 -40);
FORCEPROP 2 LAST CDS_LIB pure_quanta
J 0
(-1425 50);
DISPLAY INVISIBLE (-1425 50);
FORCEPROP 2 LAST CDS_LOCATION R27
J 0
(-1375 275);
DISPLAY 1.021277 (-1375 275);
DISPLAY INVISIBLE (-1375 275);
FORCEPROP 0 LAST $SEC 1
J 0
(-1375 250);
DISPLAY 0.680851 (-1375 250);
PAINT MONO (-1375 250);
DISPLAY INVISIBLE (-1375 250);
FORCEPROP 2 LAST CDS_SEC 1
J 0
(-1375 275);
DISPLAY 1.021277 (-1375 275);
DISPLAY INVISIBLE (-1375 275);
FORCEPROP 1 LAST PATH I10
J 0
(-1375 225);
DISPLAY 0.978723 (-1375 225);
PAINT WHITE (-1375 225);
DISPLAY INVISIBLE (-1375 225);
FORCEADD TAP..1
(0 3550);
FORCEPROP 3 LASTPIN (-50 3550) SIG_NAME M_A_CPU0_SA_DQ<18>
J 0
(-40 3560);
DISPLAY 0.659574 (-40 3560);
PAINT MONO (-40 3560);
DISPLAY INVISIBLE (-40 3560);
FORCEPROP 1 LASTPIN (-50 3550) BN 18
J 0
(-62 3558);
DISPLAY 0.680851 (-62 3558);
PAINT GREEN (-62 3558);
FORCEPROP 2 LAST CDS_LIB standard
J 0
(0 3550);
PAINT MONO (0 3550);
DISPLAY INVISIBLE (0 3550);
FORCEPROP 1 LAST BODY_TYPE PLUMBING
J 0
(0 3600);
DISPLAY 0.872340 (0 3600);
PAINT GREEN (0 3600);
DISPLAY INVISIBLE (0 3600);
FORCEPROP 1 LAST HDL_TAP TRUE
J 0
(325 3425);
DISPLAY 0.872340 (325 3425);
DISPLAY INVISIBLE (325 3425);
FORCEPROP 1 LAST PATH I100
J 0
(-2 3550);
DISPLAY 0.872340 (-2 3550);
PAINT GREEN (-2 3550);
DISPLAY INVISIBLE (-2 3550);
FORCEADD TAP..1
(0 3650);
FORCEPROP 3 LASTPIN (-50 3650) SIG_NAME M_A_CPU0_SA_DQ<20>
J 0
(-40 3660);
DISPLAY 0.659574 (-40 3660);
PAINT MONO (-40 3660);
DISPLAY INVISIBLE (-40 3660);
FORCEPROP 1 LASTPIN (-50 3650) BN 20
J 0
(-62 3658);
DISPLAY 0.680851 (-62 3658);
PAINT GREEN (-62 3658);
FORCEPROP 2 LAST CDS_LIB standard
J 0
(0 3650);
PAINT MONO (0 3650);
DISPLAY INVISIBLE (0 3650);
FORCEPROP 1 LAST BODY_TYPE PLUMBING
J 0
(0 3700);
DISPLAY 0.872340 (0 3700);
PAINT GREEN (0 3700);
DISPLAY INVISIBLE (0 3700);
FORCEPROP 1 LAST HDL_TAP TRUE
J 0
(325 3525);
DISPLAY 0.872340 (325 3525);
DISPLAY INVISIBLE (325 3525);
FORCEPROP 1 LAST PATH I101
J 0
(-2 3650);
DISPLAY 0.872340 (-2 3650);
PAINT GREEN (-2 3650);
DISPLAY INVISIBLE (-2 3650);
FORCEADD TAP..1
(0 3700);
FORCEPROP 3 LASTPIN (-50 3700) SIG_NAME M_A_CPU0_SA_DQ<21>
J 0
(-40 3710);
DISPLAY 0.659574 (-40 3710);
PAINT MONO (-40 3710);
DISPLAY INVISIBLE (-40 3710);
FORCEPROP 1 LASTPIN (-50 3700) BN 21
J 0
(-62 3708);
DISPLAY 0.680851 (-62 3708);
PAINT GREEN (-62 3708);
FORCEPROP 2 LAST CDS_LIB standard
J 0
(0 3700);
PAINT MONO (0 3700);
DISPLAY INVISIBLE (0 3700);
FORCEPROP 1 LAST BODY_TYPE PLUMBING
J 0
(0 3750);
DISPLAY 0.872340 (0 3750);
PAINT GREEN (0 3750);
DISPLAY INVISIBLE (0 3750);
FORCEPROP 1 LAST HDL_TAP TRUE
J 0
(325 3575);
DISPLAY 0.872340 (325 3575);
DISPLAY INVISIBLE (325 3575);
FORCEPROP 1 LAST PATH I102
J 0
(-2 3700);
DISPLAY 0.872340 (-2 3700);
PAINT GREEN (-2 3700);
DISPLAY INVISIBLE (-2 3700);
FORCEADD TAP..1
(0 3850);
FORCEPROP 3 LASTPIN (-50 3850) SIG_NAME M_A_CPU0_SA_DQ<24>
J 0
(-40 3860);
DISPLAY 0.659574 (-40 3860);
PAINT MONO (-40 3860);
DISPLAY INVISIBLE (-40 3860);
FORCEPROP 1 LASTPIN (-50 3850) BN 24
J 0
(-62 3858);
DISPLAY 0.680851 (-62 3858);
PAINT GREEN (-62 3858);
FORCEPROP 2 LAST CDS_LIB standard
J 0
(0 3850);
DISPLAY INVISIBLE (0 3850);
FORCEPROP 1 LAST BODY_TYPE PLUMBING
J 0
(0 3900);
DISPLAY 0.872340 (0 3900);
PAINT GREEN (0 3900);
DISPLAY INVISIBLE (0 3900);
FORCEPROP 1 LAST HDL_TAP TRUE
J 0
(325 3725);
DISPLAY 0.872340 (325 3725);
DISPLAY INVISIBLE (325 3725);
FORCEPROP 1 LAST PATH I103
J 0
(-2 3850);
DISPLAY 0.872340 (-2 3850);
PAINT GREEN (-2 3850);
DISPLAY INVISIBLE (-2 3850);
FORCEADD TAP..1
(0 3800);
FORCEPROP 3 LASTPIN (-50 3800) SIG_NAME M_A_CPU0_SA_DQ<23>
J 0
(-40 3810);
DISPLAY 0.659574 (-40 3810);
PAINT MONO (-40 3810);
DISPLAY INVISIBLE (-40 3810);
FORCEPROP 1 LASTPIN (-50 3800) BN 23
J 0
(-62 3808);
DISPLAY 0.680851 (-62 3808);
PAINT GREEN (-62 3808);
FORCEPROP 2 LAST CDS_LIB standard
J 0
(0 3800);
DISPLAY INVISIBLE (0 3800);
FORCEPROP 1 LAST BODY_TYPE PLUMBING
J 0
(0 3850);
DISPLAY 0.872340 (0 3850);
PAINT GREEN (0 3850);
DISPLAY INVISIBLE (0 3850);
FORCEPROP 1 LAST HDL_TAP TRUE
J 0
(325 3675);
DISPLAY 0.872340 (325 3675);
DISPLAY INVISIBLE (325 3675);
FORCEPROP 1 LAST PATH I104
J 0
(-2 3800);
DISPLAY 0.872340 (-2 3800);
PAINT GREEN (-2 3800);
DISPLAY INVISIBLE (-2 3800);
FORCEADD TAP..1
(0 3750);
FORCEPROP 3 LASTPIN (-50 3750) SIG_NAME M_A_CPU0_SA_DQ<22>
J 0
(-40 3760);
DISPLAY 0.659574 (-40 3760);
PAINT MONO (-40 3760);
DISPLAY INVISIBLE (-40 3760);
FORCEPROP 1 LASTPIN (-50 3750) BN 22
J 0
(-62 3758);
DISPLAY 0.680851 (-62 3758);
PAINT GREEN (-62 3758);
FORCEPROP 2 LAST CDS_LIB standard
J 0
(0 3750);
DISPLAY INVISIBLE (0 3750);
FORCEPROP 1 LAST BODY_TYPE PLUMBING
J 0
(0 3800);
DISPLAY 0.872340 (0 3800);
PAINT GREEN (0 3800);
DISPLAY INVISIBLE (0 3800);
FORCEPROP 1 LAST HDL_TAP TRUE
J 0
(325 3625);
DISPLAY 0.872340 (325 3625);
DISPLAY INVISIBLE (325 3625);
FORCEPROP 1 LAST PATH I105
J 0
(-2 3750);
DISPLAY 0.872340 (-2 3750);
PAINT GREEN (-2 3750);
DISPLAY INVISIBLE (-2 3750);
FORCEADD TAP..1
(0 3950);
FORCEPROP 3 LASTPIN (-50 3950) SIG_NAME M_A_CPU0_SA_DQ<26>
J 0
(-40 3960);
DISPLAY 0.659574 (-40 3960);
PAINT MONO (-40 3960);
DISPLAY INVISIBLE (-40 3960);
FORCEPROP 1 LASTPIN (-50 3950) BN 26
J 0
(-62 3958);
DISPLAY 0.680851 (-62 3958);
PAINT GREEN (-62 3958);
FORCEPROP 2 LAST CDS_LIB standard
J 0
(0 3950);
DISPLAY INVISIBLE (0 3950);
FORCEPROP 1 LAST BODY_TYPE PLUMBING
J 0
(0 4000);
DISPLAY 0.872340 (0 4000);
PAINT GREEN (0 4000);
DISPLAY INVISIBLE (0 4000);
FORCEPROP 1 LAST HDL_TAP TRUE
J 0
(325 3825);
DISPLAY 0.872340 (325 3825);
DISPLAY INVISIBLE (325 3825);
FORCEPROP 1 LAST PATH I106
J 0
(-2 3950);
DISPLAY 0.872340 (-2 3950);
PAINT GREEN (-2 3950);
DISPLAY INVISIBLE (-2 3950);
FORCEADD TAP..1
(0 3900);
FORCEPROP 3 LASTPIN (-50 3900) SIG_NAME M_A_CPU0_SA_DQ<25>
J 0
(-40 3910);
DISPLAY 0.659574 (-40 3910);
PAINT MONO (-40 3910);
DISPLAY INVISIBLE (-40 3910);
FORCEPROP 1 LASTPIN (-50 3900) BN 25
J 0
(-62 3908);
DISPLAY 0.680851 (-62 3908);
PAINT GREEN (-62 3908);
FORCEPROP 2 LAST CDS_LIB standard
J 0
(0 3900);
DISPLAY INVISIBLE (0 3900);
FORCEPROP 1 LAST BODY_TYPE PLUMBING
J 0
(0 3950);
DISPLAY 0.872340 (0 3950);
PAINT GREEN (0 3950);
DISPLAY INVISIBLE (0 3950);
FORCEPROP 1 LAST HDL_TAP TRUE
J 0
(325 3775);
DISPLAY 0.872340 (325 3775);
DISPLAY INVISIBLE (325 3775);
FORCEPROP 1 LAST PATH I107
J 0
(-2 3900);
DISPLAY 0.872340 (-2 3900);
PAINT GREEN (-2 3900);
DISPLAY INVISIBLE (-2 3900);
FORCEADD OFFPAGE..1
(-2575 4225);
FORCEPROP 2 LAST $XR1 82 
J 0
(-2916 4225);
DISPLAY 0.638298 (-2916 4225);
PAINT MONO (-2916 4225);
FORCEPROP 2 LAST $XR0 20 
J 0
(-2826 4225);
DISPLAY 0.638298 (-2826 4225);
PAINT MONO (-2826 4225);
FORCEPROP 2 LAST CDS_LIB standard
J 0
(-2575 4225);
PAINT MONO (-2575 4225);
DISPLAY INVISIBLE (-2575 4225);
FORCEPROP 1 LAST OFFPAGE TRUE
J 0
(-2250 4100);
DISPLAY 0.872340 (-2250 4100);
DISPLAY INVISIBLE (-2250 4100);
FORCEPROP 1 LAST COMMENT_BODY TRUE
J 0
(-2450 4125);
DISPLAY 0.872340 (-2450 4125);
PAINT GREEN (-2450 4125);
DISPLAY INVISIBLE (-2450 4125);
FORCEPROP 2 LAST PATH I108
J 0
(-2525 4300);
DISPLAY 1.021277 (-2525 4300);
DISPLAY INVISIBLE (-2525 4300);
FORCEADD TAP..1
R 2
(-1650 4050);
FORCEPROP 3 LASTPIN (-1600 4050) SIG_NAME M_A_CPU0_SA_CA<3>
J 0
(-1590 4060);
DISPLAY 0.659574 (-1590 4060);
PAINT MONO (-1590 4060);
DISPLAY INVISIBLE (-1590 4060);
FORCEPROP 1 LASTPIN (-1600 4050) BN 3
J 2
(-1588 4058);
DISPLAY 0.680851 (-1588 4058);
PAINT GREEN (-1588 4058);
FORCEPROP 2 LAST CDS_LIB standard
J 0
(-1650 4050);
DISPLAY INVISIBLE (-1650 4050);
FORCEPROP 1 LAST BODY_TYPE PLUMBING
J 2
(-1650 4100);
DISPLAY 0.872340 (-1650 4100);
PAINT GREEN (-1650 4100);
DISPLAY INVISIBLE (-1650 4100);
FORCEPROP 1 LAST HDL_TAP TRUE
J 2
(-1975 3925);
DISPLAY 0.872340 (-1975 3925);
DISPLAY INVISIBLE (-1975 3925);
FORCEPROP 1 LAST PATH I109
J 2
(-1648 4050);
DISPLAY 0.872340 (-1648 4050);
PAINT GREEN (-1648 4050);
DISPLAY INVISIBLE (-1648 4050);
FORCEADD TAP..1
R 2
(-1650 4000);
FORCEPROP 3 LASTPIN (-1600 4000) SIG_NAME M_A_CPU0_SA_CA<2>
J 0
(-1590 4010);
DISPLAY 0.659574 (-1590 4010);
PAINT MONO (-1590 4010);
DISPLAY INVISIBLE (-1590 4010);
FORCEPROP 1 LASTPIN (-1600 4000) BN 2
J 2
(-1588 4008);
DISPLAY 0.680851 (-1588 4008);
PAINT GREEN (-1588 4008);
FORCEPROP 2 LAST CDS_LIB standard
J 0
(-1650 4000);
DISPLAY INVISIBLE (-1650 4000);
FORCEPROP 1 LAST BODY_TYPE PLUMBING
J 2
(-1650 4050);
DISPLAY 0.872340 (-1650 4050);
PAINT GREEN (-1650 4050);
DISPLAY INVISIBLE (-1650 4050);
FORCEPROP 1 LAST HDL_TAP TRUE
J 2
(-1975 3875);
DISPLAY 0.872340 (-1975 3875);
DISPLAY INVISIBLE (-1975 3875);
FORCEPROP 1 LAST PATH I110
J 2
(-1648 4000);
DISPLAY 0.872340 (-1648 4000);
PAINT GREEN (-1648 4000);
DISPLAY INVISIBLE (-1648 4000);
FORCEADD TAP..1
R 2
(-1650 4100);
FORCEPROP 3 LASTPIN (-1600 4100) SIG_NAME M_A_CPU0_SA_CA<4>
J 0
(-1590 4110);
DISPLAY 0.659574 (-1590 4110);
PAINT MONO (-1590 4110);
DISPLAY INVISIBLE (-1590 4110);
FORCEPROP 1 LASTPIN (-1600 4100) BN 4
J 2
(-1588 4108);
DISPLAY 0.680851 (-1588 4108);
PAINT GREEN (-1588 4108);
FORCEPROP 2 LAST CDS_LIB standard
J 0
(-1650 4100);
DISPLAY INVISIBLE (-1650 4100);
FORCEPROP 1 LAST BODY_TYPE PLUMBING
J 2
(-1650 4150);
DISPLAY 0.872340 (-1650 4150);
PAINT GREEN (-1650 4150);
DISPLAY INVISIBLE (-1650 4150);
FORCEPROP 1 LAST HDL_TAP TRUE
J 2
(-1975 3975);
DISPLAY 0.872340 (-1975 3975);
DISPLAY INVISIBLE (-1975 3975);
FORCEPROP 1 LAST PATH I111
J 2
(-1648 4100);
DISPLAY 0.872340 (-1648 4100);
PAINT GREEN (-1648 4100);
DISPLAY INVISIBLE (-1648 4100);
FORCEADD TAP..1
R 2
(-1650 4200);
FORCEPROP 3 LASTPIN (-1600 4200) SIG_NAME M_A_CPU0_SA_CA<6>
J 0
(-1590 4210);
DISPLAY 0.659574 (-1590 4210);
PAINT MONO (-1590 4210);
DISPLAY INVISIBLE (-1590 4210);
FORCEPROP 1 LASTPIN (-1600 4200) BN 6
J 2
(-1588 4208);
DISPLAY 0.680851 (-1588 4208);
PAINT GREEN (-1588 4208);
FORCEPROP 2 LAST CDS_LIB standard
J 0
(-1650 4200);
DISPLAY INVISIBLE (-1650 4200);
FORCEPROP 1 LAST BODY_TYPE PLUMBING
J 2
(-1650 4250);
DISPLAY 0.872340 (-1650 4250);
PAINT GREEN (-1650 4250);
DISPLAY INVISIBLE (-1650 4250);
FORCEPROP 1 LAST HDL_TAP TRUE
J 2
(-1975 4075);
DISPLAY 0.872340 (-1975 4075);
DISPLAY INVISIBLE (-1975 4075);
FORCEPROP 1 LAST PATH I112
J 2
(-1648 4200);
DISPLAY 0.872340 (-1648 4200);
PAINT GREEN (-1648 4200);
DISPLAY INVISIBLE (-1648 4200);
FORCEADD TAP..1
R 2
(-1650 4150);
FORCEPROP 3 LASTPIN (-1600 4150) SIG_NAME M_A_CPU0_SA_CA<5>
J 0
(-1590 4160);
DISPLAY 0.659574 (-1590 4160);
PAINT MONO (-1590 4160);
DISPLAY INVISIBLE (-1590 4160);
FORCEPROP 1 LASTPIN (-1600 4150) BN 5
J 2
(-1588 4158);
DISPLAY 0.680851 (-1588 4158);
PAINT GREEN (-1588 4158);
FORCEPROP 2 LAST CDS_LIB standard
J 0
(-1650 4150);
DISPLAY INVISIBLE (-1650 4150);
FORCEPROP 1 LAST BODY_TYPE PLUMBING
J 2
(-1650 4200);
DISPLAY 0.872340 (-1650 4200);
PAINT GREEN (-1650 4200);
DISPLAY INVISIBLE (-1650 4200);
FORCEPROP 1 LAST HDL_TAP TRUE
J 2
(-1975 4025);
DISPLAY 0.872340 (-1975 4025);
DISPLAY INVISIBLE (-1975 4025);
FORCEPROP 1 LAST PATH I113
J 2
(-1648 4150);
DISPLAY 0.872340 (-1648 4150);
PAINT GREEN (-1648 4150);
DISPLAY INVISIBLE (-1648 4150);
FORCEADD TAP..1
(0 4000);
FORCEPROP 3 LASTPIN (-50 4000) SIG_NAME M_A_CPU0_SA_DQ<27>
J 0
(-40 4010);
DISPLAY 0.659574 (-40 4010);
PAINT MONO (-40 4010);
DISPLAY INVISIBLE (-40 4010);
FORCEPROP 1 LASTPIN (-50 4000) BN 27
J 0
(-62 4008);
DISPLAY 0.680851 (-62 4008);
PAINT GREEN (-62 4008);
FORCEPROP 2 LAST CDS_LIB standard
J 0
(0 4000);
DISPLAY INVISIBLE (0 4000);
FORCEPROP 1 LAST BODY_TYPE PLUMBING
J 0
(0 4050);
DISPLAY 0.872340 (0 4050);
PAINT GREEN (0 4050);
DISPLAY INVISIBLE (0 4050);
FORCEPROP 1 LAST HDL_TAP TRUE
J 0
(325 3875);
DISPLAY 0.872340 (325 3875);
DISPLAY INVISIBLE (325 3875);
FORCEPROP 1 LAST PATH I114
J 0
(-2 4000);
DISPLAY 0.872340 (-2 4000);
PAINT GREEN (-2 4000);
DISPLAY INVISIBLE (-2 4000);
FORCEADD TAP..1
(0 4050);
FORCEPROP 3 LASTPIN (-50 4050) SIG_NAME M_A_CPU0_SA_DQ<28>
J 0
(-40 4060);
DISPLAY 0.659574 (-40 4060);
PAINT MONO (-40 4060);
DISPLAY INVISIBLE (-40 4060);
FORCEPROP 1 LASTPIN (-50 4050) BN 28
J 0
(-62 4058);
DISPLAY 0.680851 (-62 4058);
PAINT GREEN (-62 4058);
FORCEPROP 2 LAST CDS_LIB standard
J 0
(0 4050);
DISPLAY INVISIBLE (0 4050);
FORCEPROP 1 LAST BODY_TYPE PLUMBING
J 0
(0 4100);
DISPLAY 0.872340 (0 4100);
PAINT GREEN (0 4100);
DISPLAY INVISIBLE (0 4100);
FORCEPROP 1 LAST HDL_TAP TRUE
J 0
(325 3925);
DISPLAY 0.872340 (325 3925);
DISPLAY INVISIBLE (325 3925);
FORCEPROP 1 LAST PATH I115
J 0
(-2 4050);
DISPLAY 0.872340 (-2 4050);
PAINT GREEN (-2 4050);
DISPLAY INVISIBLE (-2 4050);
FORCEADD TAP..1
(0 4100);
FORCEPROP 3 LASTPIN (-50 4100) SIG_NAME M_A_CPU0_SA_DQ<29>
J 0
(-40 4110);
DISPLAY 0.659574 (-40 4110);
PAINT MONO (-40 4110);
DISPLAY INVISIBLE (-40 4110);
FORCEPROP 1 LASTPIN (-50 4100) BN 29
J 0
(-62 4108);
DISPLAY 0.680851 (-62 4108);
PAINT GREEN (-62 4108);
FORCEPROP 2 LAST CDS_LIB standard
J 0
(0 4100);
DISPLAY INVISIBLE (0 4100);
FORCEPROP 1 LAST BODY_TYPE PLUMBING
J 0
(0 4150);
DISPLAY 0.872340 (0 4150);
PAINT GREEN (0 4150);
DISPLAY INVISIBLE (0 4150);
FORCEPROP 1 LAST HDL_TAP TRUE
J 0
(325 3975);
DISPLAY 0.872340 (325 3975);
DISPLAY INVISIBLE (325 3975);
FORCEPROP 1 LAST PATH I116
J 0
(-2 4100);
DISPLAY 0.872340 (-2 4100);
PAINT GREEN (-2 4100);
DISPLAY INVISIBLE (-2 4100);
FORCEADD TAP..1
(0 4200);
FORCEPROP 3 LASTPIN (-50 4200) SIG_NAME M_A_CPU0_SA_DQ<31>
J 0
(-40 4210);
DISPLAY 0.659574 (-40 4210);
PAINT MONO (-40 4210);
DISPLAY INVISIBLE (-40 4210);
FORCEPROP 1 LASTPIN (-50 4200) BN 31
J 0
(-62 4208);
DISPLAY 0.680851 (-62 4208);
PAINT GREEN (-62 4208);
FORCEPROP 2 LAST CDS_LIB standard
J 0
(0 4200);
DISPLAY INVISIBLE (0 4200);
FORCEPROP 1 LAST BODY_TYPE PLUMBING
J 0
(0 4250);
DISPLAY 0.872340 (0 4250);
PAINT GREEN (0 4250);
DISPLAY INVISIBLE (0 4250);
FORCEPROP 1 LAST HDL_TAP TRUE
J 0
(325 4075);
DISPLAY 0.872340 (325 4075);
DISPLAY INVISIBLE (325 4075);
FORCEPROP 1 LAST PATH I117
J 0
(-2 4200);
DISPLAY 0.872340 (-2 4200);
PAINT GREEN (-2 4200);
DISPLAY INVISIBLE (-2 4200);
FORCEADD TAP..1
(0 4150);
FORCEPROP 3 LASTPIN (-50 4150) SIG_NAME M_A_CPU0_SA_DQ<30>
J 0
(-40 4160);
DISPLAY 0.659574 (-40 4160);
PAINT MONO (-40 4160);
DISPLAY INVISIBLE (-40 4160);
FORCEPROP 1 LASTPIN (-50 4150) BN 30
J 0
(-62 4158);
DISPLAY 0.680851 (-62 4158);
PAINT GREEN (-62 4158);
FORCEPROP 2 LAST CDS_LIB standard
J 0
(0 4150);
DISPLAY INVISIBLE (0 4150);
FORCEPROP 1 LAST BODY_TYPE PLUMBING
J 0
(0 4200);
DISPLAY 0.872340 (0 4200);
PAINT GREEN (0 4200);
DISPLAY INVISIBLE (0 4200);
FORCEPROP 1 LAST HDL_TAP TRUE
J 0
(325 4025);
DISPLAY 0.872340 (325 4025);
DISPLAY INVISIBLE (325 4025);
FORCEPROP 1 LAST PATH I118
J 0
(-2 4150);
DISPLAY 0.872340 (-2 4150);
PAINT GREEN (-2 4150);
DISPLAY INVISIBLE (-2 4150);
FORCEADD VCC_CORE..1
(1725 650);
FORCEPROP 3 LASTPIN (1725 600) SIG_NAME P3V3_AUX\g
J 0
(1735 610);
DISPLAY 0.659574 (1735 610);
PAINT MONO (1735 610);
DISPLAY INVISIBLE (1735 610);
FORCEPROP 1 LAST HDL_POWER P3V3_AUX
J 1
(1725 700);
DISPLAY 1.148936 (1725 700);
PAINT GREEN (1725 700);
FORCEPROP 2 LAST CDS_LIB logical_power
J 0
(1725 650);
PAINT MONO (1725 650);
DISPLAY INVISIBLE (1725 650);
FORCEPROP 1 LAST PATH I119
J 0
(1775 675);
DISPLAY 0.872340 (1775 675);
PAINT AQUA (1775 675);
DISPLAY INVISIBLE (1775 675);
FORCEADD OFFPAGE..3
R 2
(-2575 2375);
FORCEPROP 2 LAST $XR1 82 
J 0
(-2944 2375);
DISPLAY 0.638298 (-2944 2375);
PAINT MONO (-2944 2375);
FORCEPROP 2 LAST $XR0 20 
J 0
(-2854 2375);
DISPLAY 0.638298 (-2854 2375);
PAINT MONO (-2854 2375);
FORCEPROP 2 LAST CDS_LIB standard
J 0
(-2575 2375);
PAINT MONO (-2575 2375);
DISPLAY INVISIBLE (-2575 2375);
FORCEPROP 1 LAST OFFPAGE TRUE
J 2
(-2900 2250);
DISPLAY 0.872340 (-2900 2250);
DISPLAY INVISIBLE (-2900 2250);
FORCEPROP 1 LAST COMMENT_BODY TRUE
J 2
(-2525 2275);
DISPLAY 0.872340 (-2525 2275);
PAINT GREEN (-2525 2275);
DISPLAY INVISIBLE (-2525 2275);
FORCEPROP 2 LAST PATH I12
J 0
(-2525 2450);
DISPLAY 1.021277 (-2525 2450);
DISPLAY INVISIBLE (-2525 2450);
FORCEADD Q_CAP..1
(1725 325);
FORCEPROP 1 LAST PART_NUMBER CH5221MEB00
J 0
(1775 175);
DISPLAY 0.978723 (1775 175);
DISPLAY INVISIBLE (1775 175);
FORCEPROP 1 LAST PACK_TYPE C0402
J 0
(1775 125);
DISPLAY 0.978723 (1775 125);
FORCEPROP 1 LAST VOLTAGE 6.3V
J 0
(1775 325);
DISPLAY 0.978723 (1775 325);
FORCEPROP 1 LAST MATERIAL X6S
J 0
(1775 225);
DISPLAY 0.978723 (1775 225);
FORCEPROP 1 LAST VALUE 2.2UF
J 0
(1775 375);
DISPLAY 0.978723 (1775 375);
FORCEPROP 1 LAST TOLERANCE 20%
J 0
(1775 275);
DISPLAY 0.978723 (1775 275);
FORCEPROP 1 LAST $LOCATION C5
J 0
(1775 425);
DISPLAY 0.978723 (1775 425);
FORCEPROP 1 LASTPIN (1725 425) $PN 1
J 0
(1735 405);
DISPLAY 0.787234 (1735 405);
FORCEPROP 1 LASTPIN (1725 225) $PN 2
J 0
(1735 205);
DISPLAY 0.787234 (1735 205);
FORCEPROP 2 LAST CDS_LIB pure_quanta
J 0
(1725 325);
PAINT MONO (1725 325);
DISPLAY INVISIBLE (1725 325);
FORCEPROP 2 LAST CDS_LOCATION C5
J 0
(1775 525);
DISPLAY 1.021277 (1775 525);
DISPLAY INVISIBLE (1775 525);
FORCEPROP 2 LAST $SEC 1
J 0
(1775 525);
DISPLAY 0.680851 (1775 525);
PAINT MONO (1775 525);
DISPLAY INVISIBLE (1775 525);
FORCEPROP 2 LAST CDS_SEC 1
J 0
(1775 525);
DISPLAY 1.021277 (1775 525);
DISPLAY INVISIBLE (1775 525);
FORCEPROP 1 LAST PATH I120
J 0
(1775 475);
DISPLAY 0.978723 (1775 475);
PAINT WHITE (1775 475);
DISPLAY INVISIBLE (1775 475);
FORCEADD UNIVERSAL_GND..1
(1725 -50);
FORCEPROP 3 LASTPIN (1725 0) SIG_NAME GND\g
J 0
(1735 10);
DISPLAY 0.659574 (1735 10);
PAINT MONO (1735 10);
DISPLAY INVISIBLE (1735 10);
FORCEPROP 2 LAST CDS_LIB logical_power
J 0
(1725 -50);
PAINT MONO (1725 -50);
DISPLAY INVISIBLE (1725 -50);
FORCEPROP 1 LAST HDL_POWER GND
J 1
(1750 -125);
DISPLAY 0.872340 (1750 -125);
PAINT GREEN (1750 -125);
DISPLAY INVISIBLE (1750 -125);
FORCEPROP 1 LAST PATH I121
J 0
(1800 -50);
DISPLAY 0.872340 (1800 -50);
PAINT AQUA (1800 -50);
DISPLAY INVISIBLE (1800 -50);
FORCEADD Q_CAP..1
(2725 325);
FORCEPROP 1 LAST PART_NUMBER CH6103KEA00
J 0
(2775 175);
DISPLAY 0.978723 (2775 175);
DISPLAY INVISIBLE (2775 175);
FORCEPROP 1 LAST MATERIAL X6S
J 0
(2775 225);
DISPLAY 0.978723 (2775 225);
FORCEPROP 1 LAST TOLERANCE 10%
J 0
(2775 275);
DISPLAY 0.978723 (2775 275);
FORCEPROP 1 LAST VALUE 10UF
J 0
(2775 375);
DISPLAY 0.978723 (2775 375);
FORCEPROP 1 LAST PACK_TYPE C0805
J 0
(2775 125);
DISPLAY 0.978723 (2775 125);
FORCEPROP 1 LAST VOLTAGE 16V
J 0
(2775 325);
DISPLAY 0.978723 (2775 325);
FORCEPROP 1 LAST $LOCATION C6
J 0
(2775 425);
DISPLAY 0.978723 (2775 425);
FORCEPROP 1 LASTPIN (2725 425) $PN 1
J 0
(2735 405);
DISPLAY 0.787234 (2735 405);
FORCEPROP 1 LASTPIN (2725 225) $PN 2
J 0
(2735 205);
DISPLAY 0.787234 (2735 205);
FORCEPROP 2 LAST CDS_LIB pure_quanta
J 0
(2725 325);
PAINT MONO (2725 325);
DISPLAY INVISIBLE (2725 325);
FORCEPROP 2 LAST CDS_LOCATION C6
J 0
(2775 525);
DISPLAY 1.021277 (2775 525);
DISPLAY INVISIBLE (2775 525);
FORCEPROP 2 LAST $SEC 1
J 0
(2775 525);
DISPLAY 0.680851 (2775 525);
PAINT MONO (2775 525);
DISPLAY INVISIBLE (2775 525);
FORCEPROP 2 LAST CDS_SEC 1
J 0
(2775 525);
DISPLAY 1.021277 (2775 525);
DISPLAY INVISIBLE (2775 525);
FORCEPROP 1 LAST PATH I122
J 0
(2775 475);
DISPLAY 0.978723 (2775 475);
PAINT WHITE (2775 475);
DISPLAY INVISIBLE (2775 475);
FORCEADD VCC_CORE..1
(2725 650);
FORCEPROP 3 LASTPIN (2725 600) SIG_NAME P12V_S3_AUX_CPU0_NVDIMM\g
J 0
(2735 610);
DISPLAY 0.659574 (2735 610);
PAINT MONO (2735 610);
DISPLAY INVISIBLE (2735 610);
FORCEPROP 1 LAST HDL_POWER P12V_S3_AUX_CPU0_NVDIMM
J 1
(2725 700);
DISPLAY 1.148936 (2725 700);
PAINT GREEN (2725 700);
FORCEPROP 2 LAST CDS_LIB logical_power
J 0
(2725 650);
PAINT MONO (2725 650);
DISPLAY INVISIBLE (2725 650);
FORCEPROP 1 LAST PATH I123
J 0
(2775 675);
DISPLAY 0.872340 (2775 675);
PAINT AQUA (2775 675);
DISPLAY INVISIBLE (2775 675);
FORCEADD OFFPAGE..3
(825 2575);
FORCEPROP 2 LAST $XR1 82 
J 0
(1129 2575);
DISPLAY 0.638298 (1129 2575);
PAINT MONO (1129 2575);
FORCEPROP 2 LAST $XR0 20 
J 0
(1039 2575);
DISPLAY 0.638298 (1039 2575);
PAINT MONO (1039 2575);
FORCEPROP 2 LAST CDS_LIB standard
J 2
(825 2575);
DISPLAY INVISIBLE (825 2575);
FORCEPROP 1 LAST OFFPAGE TRUE
J 0
(1150 2450);
DISPLAY 0.872340 (1150 2450);
DISPLAY INVISIBLE (1150 2450);
FORCEPROP 1 LAST COMMENT_BODY TRUE
J 0
(775 2475);
DISPLAY 0.872340 (775 2475);
PAINT GREEN (775 2475);
DISPLAY INVISIBLE (775 2475);
FORCEPROP 2 LAST PATH I124
J 0
(1025 2650);
DISPLAY 1.021277 (1025 2650);
DISPLAY INVISIBLE (1025 2650);
FORCEADD TAP..1
(2725 2250);
FORCEPROP 3 LASTPIN (2675 2250) SIG_NAME M_A_CPU0_SB_DQS_DP<0>
J 0
(2685 2260);
DISPLAY 0.659574 (2685 2260);
PAINT MONO (2685 2260);
DISPLAY INVISIBLE (2685 2260);
FORCEPROP 1 LASTPIN (2675 2250) BN 0
J 0
(2663 2258);
DISPLAY 0.680851 (2663 2258);
PAINT GREEN (2663 2258);
FORCEPROP 2 LAST CDS_LIB standard
J 0
(2725 2250);
PAINT MONO (2725 2250);
DISPLAY INVISIBLE (2725 2250);
FORCEPROP 1 LAST BODY_TYPE PLUMBING
J 0
(2725 2300);
DISPLAY 0.872340 (2725 2300);
PAINT GREEN (2725 2300);
DISPLAY INVISIBLE (2725 2300);
FORCEPROP 1 LAST HDL_TAP TRUE
J 0
(3050 2125);
DISPLAY 0.872340 (3050 2125);
DISPLAY INVISIBLE (3050 2125);
FORCEPROP 1 LAST PATH I126
J 0
(2723 2250);
DISPLAY 0.872340 (2723 2250);
PAINT GREEN (2723 2250);
DISPLAY INVISIBLE (2723 2250);
FORCEADD TAP..1
(2725 2450);
FORCEPROP 3 LASTPIN (2675 2450) SIG_NAME M_A_CPU0_SB_DQS_DP<2>
J 0
(2685 2460);
DISPLAY 0.659574 (2685 2460);
PAINT MONO (2685 2460);
DISPLAY INVISIBLE (2685 2460);
FORCEPROP 1 LASTPIN (2675 2450) BN 2
J 0
(2663 2458);
DISPLAY 0.680851 (2663 2458);
PAINT GREEN (2663 2458);
FORCEPROP 2 LAST CDS_LIB standard
J 0
(2725 2450);
DISPLAY INVISIBLE (2725 2450);
FORCEPROP 1 LAST BODY_TYPE PLUMBING
J 0
(2725 2500);
DISPLAY 0.872340 (2725 2500);
PAINT GREEN (2725 2500);
DISPLAY INVISIBLE (2725 2500);
FORCEPROP 1 LAST HDL_TAP TRUE
J 0
(3050 2325);
DISPLAY 0.872340 (3050 2325);
DISPLAY INVISIBLE (3050 2325);
FORCEPROP 1 LAST PATH I127
J 0
(2723 2450);
DISPLAY 0.872340 (2723 2450);
PAINT GREEN (2723 2450);
DISPLAY INVISIBLE (2723 2450);
FORCEADD TAP..1
(2725 2350);
FORCEPROP 3 LASTPIN (2675 2350) SIG_NAME M_A_CPU0_SB_DQS_DP<1>
J 0
(2685 2360);
DISPLAY 0.659574 (2685 2360);
PAINT MONO (2685 2360);
DISPLAY INVISIBLE (2685 2360);
FORCEPROP 1 LASTPIN (2675 2350) BN 1
J 0
(2663 2358);
DISPLAY 0.680851 (2663 2358);
PAINT GREEN (2663 2358);
FORCEPROP 2 LAST CDS_LIB standard
J 0
(2725 2350);
DISPLAY INVISIBLE (2725 2350);
FORCEPROP 1 LAST BODY_TYPE PLUMBING
J 0
(2725 2400);
DISPLAY 0.872340 (2725 2400);
PAINT GREEN (2725 2400);
DISPLAY INVISIBLE (2725 2400);
FORCEPROP 1 LAST HDL_TAP TRUE
J 0
(3050 2225);
DISPLAY 0.872340 (3050 2225);
DISPLAY INVISIBLE (3050 2225);
FORCEPROP 1 LAST PATH I128
J 0
(2723 2350);
DISPLAY 0.872340 (2723 2350);
PAINT GREEN (2723 2350);
DISPLAY INVISIBLE (2723 2350);
FORCEADD TAP..1
(2725 2550);
FORCEPROP 3 LASTPIN (2675 2550) SIG_NAME M_A_CPU0_SB_DQS_DP<3>
J 0
(2685 2560);
DISPLAY 0.659574 (2685 2560);
PAINT MONO (2685 2560);
DISPLAY INVISIBLE (2685 2560);
FORCEPROP 1 LASTPIN (2675 2550) BN 3
J 0
(2663 2558);
DISPLAY 0.680851 (2663 2558);
PAINT GREEN (2663 2558);
FORCEPROP 2 LAST CDS_LIB standard
J 0
(2725 2550);
PAINT MONO (2725 2550);
DISPLAY INVISIBLE (2725 2550);
FORCEPROP 1 LAST BODY_TYPE PLUMBING
J 0
(2725 2600);
DISPLAY 0.872340 (2725 2600);
PAINT GREEN (2725 2600);
DISPLAY INVISIBLE (2725 2600);
FORCEPROP 1 LAST HDL_TAP TRUE
J 0
(3050 2425);
DISPLAY 0.872340 (3050 2425);
DISPLAY INVISIBLE (3050 2425);
FORCEPROP 1 LAST PATH I129
J 0
(2723 2550);
DISPLAY 0.872340 (2723 2550);
PAINT GREEN (2723 2550);
DISPLAY INVISIBLE (2723 2550);
FORCEADD VCC_CORE..1
(-2475 2075);
FORCEPROP 3 LASTPIN (-2475 2025) SIG_NAME P3V3_AUX\g
J 0
(-2465 2035);
DISPLAY 0.659574 (-2465 2035);
PAINT MONO (-2465 2035);
DISPLAY INVISIBLE (-2465 2035);
FORCEPROP 1 LAST HDL_POWER P3V3_AUX
J 1
(-2475 2125);
DISPLAY 1.148936 (-2475 2125);
PAINT GREEN (-2475 2125);
FORCEPROP 2 LAST CDS_LIB logical_power
J 0
(-2475 2075);
PAINT MONO (-2475 2075);
DISPLAY INVISIBLE (-2475 2075);
FORCEPROP 1 LAST PATH I13
J 0
(-2425 2100);
DISPLAY 0.872340 (-2425 2100);
PAINT AQUA (-2425 2100);
DISPLAY INVISIBLE (-2425 2100);
FORCEADD TAP..1
(2725 2650);
FORCEPROP 3 LASTPIN (2675 2650) SIG_NAME M_A_CPU0_SB_DQS_DP<4>
J 0
(2685 2660);
DISPLAY 0.659574 (2685 2660);
PAINT MONO (2685 2660);
DISPLAY INVISIBLE (2685 2660);
FORCEPROP 1 LASTPIN (2675 2650) BN 4
J 0
(2663 2658);
DISPLAY 0.680851 (2663 2658);
PAINT GREEN (2663 2658);
FORCEPROP 2 LAST CDS_LIB standard
J 0
(2725 2650);
PAINT MONO (2725 2650);
DISPLAY INVISIBLE (2725 2650);
FORCEPROP 1 LAST BODY_TYPE PLUMBING
J 0
(2725 2700);
DISPLAY 0.872340 (2725 2700);
PAINT GREEN (2725 2700);
DISPLAY INVISIBLE (2725 2700);
FORCEPROP 1 LAST HDL_TAP TRUE
J 0
(3050 2525);
DISPLAY 0.872340 (3050 2525);
DISPLAY INVISIBLE (3050 2525);
FORCEPROP 1 LAST PATH I130
J 0
(2723 2650);
DISPLAY 0.872340 (2723 2650);
PAINT GREEN (2723 2650);
DISPLAY INVISIBLE (2723 2650);
FORCEADD TAP..1
(2725 2750);
FORCEPROP 3 LASTPIN (2675 2750) SIG_NAME M_A_CPU0_SB_DQS_DP<5>
J 0
(2685 2760);
DISPLAY 0.659574 (2685 2760);
PAINT MONO (2685 2760);
DISPLAY INVISIBLE (2685 2760);
FORCEPROP 1 LASTPIN (2675 2750) BN 5
J 0
(2663 2758);
DISPLAY 0.680851 (2663 2758);
PAINT GREEN (2663 2758);
FORCEPROP 2 LAST CDS_LIB standard
J 0
(2725 2750);
DISPLAY INVISIBLE (2725 2750);
FORCEPROP 1 LAST BODY_TYPE PLUMBING
J 0
(2725 2800);
DISPLAY 0.872340 (2725 2800);
PAINT GREEN (2725 2800);
DISPLAY INVISIBLE (2725 2800);
FORCEPROP 1 LAST HDL_TAP TRUE
J 0
(3050 2625);
DISPLAY 0.872340 (3050 2625);
DISPLAY INVISIBLE (3050 2625);
FORCEPROP 1 LAST PATH I131
J 0
(2723 2750);
DISPLAY 0.872340 (2723 2750);
PAINT GREEN (2723 2750);
DISPLAY INVISIBLE (2723 2750);
FORCEADD TAP..1
(2725 2950);
FORCEPROP 3 LASTPIN (2675 2950) SIG_NAME M_A_CPU0_SB_DQS_DP<7>
J 0
(2685 2960);
DISPLAY 0.659574 (2685 2960);
PAINT MONO (2685 2960);
DISPLAY INVISIBLE (2685 2960);
FORCEPROP 1 LASTPIN (2675 2950) BN 7
J 0
(2663 2958);
DISPLAY 0.680851 (2663 2958);
PAINT GREEN (2663 2958);
FORCEPROP 2 LAST CDS_LIB standard
J 0
(2725 2950);
DISPLAY INVISIBLE (2725 2950);
FORCEPROP 1 LAST BODY_TYPE PLUMBING
J 0
(2725 3000);
DISPLAY 0.872340 (2725 3000);
PAINT GREEN (2725 3000);
DISPLAY INVISIBLE (2725 3000);
FORCEPROP 1 LAST HDL_TAP TRUE
J 0
(3050 2825);
DISPLAY 0.872340 (3050 2825);
DISPLAY INVISIBLE (3050 2825);
FORCEPROP 1 LAST PATH I132
J 0
(2723 2950);
DISPLAY 0.872340 (2723 2950);
PAINT GREEN (2723 2950);
DISPLAY INVISIBLE (2723 2950);
FORCEADD TAP..1
(2725 2850);
FORCEPROP 3 LASTPIN (2675 2850) SIG_NAME M_A_CPU0_SB_DQS_DP<6>
J 0
(2685 2860);
DISPLAY 0.659574 (2685 2860);
PAINT MONO (2685 2860);
DISPLAY INVISIBLE (2685 2860);
FORCEPROP 1 LASTPIN (2675 2850) BN 6
J 0
(2663 2858);
DISPLAY 0.680851 (2663 2858);
PAINT GREEN (2663 2858);
FORCEPROP 2 LAST CDS_LIB standard
J 0
(2725 2850);
DISPLAY INVISIBLE (2725 2850);
FORCEPROP 1 LAST BODY_TYPE PLUMBING
J 0
(2725 2900);
DISPLAY 0.872340 (2725 2900);
PAINT GREEN (2725 2900);
DISPLAY INVISIBLE (2725 2900);
FORCEPROP 1 LAST HDL_TAP TRUE
J 0
(3050 2725);
DISPLAY 0.872340 (3050 2725);
DISPLAY INVISIBLE (3050 2725);
FORCEPROP 1 LAST PATH I133
J 0
(2723 2850);
DISPLAY 0.872340 (2723 2850);
PAINT GREEN (2723 2850);
DISPLAY INVISIBLE (2723 2850);
FORCEADD TAP..1
(2725 3050);
FORCEPROP 3 LASTPIN (2675 3050) SIG_NAME M_A_CPU0_SB_DQS_DP<8>
J 0
(2685 3060);
DISPLAY 0.659574 (2685 3060);
PAINT MONO (2685 3060);
DISPLAY INVISIBLE (2685 3060);
FORCEPROP 1 LASTPIN (2675 3050) BN 8
J 0
(2663 3058);
DISPLAY 0.680851 (2663 3058);
PAINT GREEN (2663 3058);
FORCEPROP 2 LAST CDS_LIB standard
J 0
(2725 3050);
DISPLAY INVISIBLE (2725 3050);
FORCEPROP 1 LAST BODY_TYPE PLUMBING
J 0
(2725 3100);
DISPLAY 0.872340 (2725 3100);
PAINT GREEN (2725 3100);
DISPLAY INVISIBLE (2725 3100);
FORCEPROP 1 LAST HDL_TAP TRUE
J 0
(3050 2925);
DISPLAY 0.872340 (3050 2925);
DISPLAY INVISIBLE (3050 2925);
FORCEPROP 1 LAST PATH I134
J 0
(2723 3050);
DISPLAY 0.872340 (2723 3050);
PAINT GREEN (2723 3050);
DISPLAY INVISIBLE (2723 3050);
FORCEADD TAP..1
(2725 3150);
FORCEPROP 3 LASTPIN (2675 3150) SIG_NAME M_A_CPU0_SB_DQS_DP<9>
J 0
(2685 3160);
DISPLAY 0.659574 (2685 3160);
PAINT MONO (2685 3160);
DISPLAY INVISIBLE (2685 3160);
FORCEPROP 1 LASTPIN (2675 3150) BN 9
J 0
(2663 3158);
DISPLAY 0.680851 (2663 3158);
PAINT GREEN (2663 3158);
FORCEPROP 2 LAST CDS_LIB standard
J 0
(2725 3150);
DISPLAY INVISIBLE (2725 3150);
FORCEPROP 1 LAST BODY_TYPE PLUMBING
J 0
(2725 3200);
DISPLAY 0.872340 (2725 3200);
PAINT GREEN (2725 3200);
DISPLAY INVISIBLE (2725 3200);
FORCEPROP 1 LAST HDL_TAP TRUE
J 0
(3050 3025);
DISPLAY 0.872340 (3050 3025);
DISPLAY INVISIBLE (3050 3025);
FORCEPROP 1 LAST PATH I135
J 0
(2723 3150);
DISPLAY 0.872340 (2723 3150);
PAINT GREEN (2723 3150);
DISPLAY INVISIBLE (2723 3150);
FORCEADD TAP..1
(2725 3300);
FORCEPROP 3 LASTPIN (2675 3300) SIG_NAME M_A_CPU0_SA_DQS_DP<0>
J 0
(2685 3310);
DISPLAY 0.659574 (2685 3310);
PAINT MONO (2685 3310);
DISPLAY INVISIBLE (2685 3310);
FORCEPROP 1 LASTPIN (2675 3300) BN 0
J 0
(2663 3308);
DISPLAY 0.680851 (2663 3308);
PAINT GREEN (2663 3308);
FORCEPROP 2 LAST CDS_LIB standard
J 0
(2725 3300);
PAINT MONO (2725 3300);
DISPLAY INVISIBLE (2725 3300);
FORCEPROP 1 LAST BODY_TYPE PLUMBING
J 0
(2725 3350);
DISPLAY 0.872340 (2725 3350);
PAINT GREEN (2725 3350);
DISPLAY INVISIBLE (2725 3350);
FORCEPROP 1 LAST HDL_TAP TRUE
J 0
(3050 3175);
DISPLAY 0.872340 (3050 3175);
DISPLAY INVISIBLE (3050 3175);
FORCEPROP 1 LAST PATH I136
J 0
(2723 3300);
DISPLAY 0.872340 (2723 3300);
PAINT GREEN (2723 3300);
DISPLAY INVISIBLE (2723 3300);
FORCEADD TAP..1
(2725 3400);
FORCEPROP 3 LASTPIN (2675 3400) SIG_NAME M_A_CPU0_SA_DQS_DP<1>
J 0
(2685 3410);
DISPLAY 0.659574 (2685 3410);
PAINT MONO (2685 3410);
DISPLAY INVISIBLE (2685 3410);
FORCEPROP 1 LASTPIN (2675 3400) BN 1
J 0
(2663 3408);
DISPLAY 0.680851 (2663 3408);
PAINT GREEN (2663 3408);
FORCEPROP 2 LAST CDS_LIB standard
J 0
(2725 3400);
DISPLAY INVISIBLE (2725 3400);
FORCEPROP 1 LAST BODY_TYPE PLUMBING
J 0
(2725 3450);
DISPLAY 0.872340 (2725 3450);
PAINT GREEN (2725 3450);
DISPLAY INVISIBLE (2725 3450);
FORCEPROP 1 LAST HDL_TAP TRUE
J 0
(3050 3275);
DISPLAY 0.872340 (3050 3275);
DISPLAY INVISIBLE (3050 3275);
FORCEPROP 1 LAST PATH I137
J 0
(2723 3400);
DISPLAY 0.872340 (2723 3400);
PAINT GREEN (2723 3400);
DISPLAY INVISIBLE (2723 3400);
FORCEADD TAP..1
(2725 3500);
FORCEPROP 3 LASTPIN (2675 3500) SIG_NAME M_A_CPU0_SA_DQS_DP<2>
J 0
(2685 3510);
DISPLAY 0.659574 (2685 3510);
PAINT MONO (2685 3510);
DISPLAY INVISIBLE (2685 3510);
FORCEPROP 1 LASTPIN (2675 3500) BN 2
J 0
(2663 3508);
DISPLAY 0.680851 (2663 3508);
PAINT GREEN (2663 3508);
FORCEPROP 2 LAST CDS_LIB standard
J 0
(2725 3500);
DISPLAY INVISIBLE (2725 3500);
FORCEPROP 1 LAST BODY_TYPE PLUMBING
J 0
(2725 3550);
DISPLAY 0.872340 (2725 3550);
PAINT GREEN (2725 3550);
DISPLAY INVISIBLE (2725 3550);
FORCEPROP 1 LAST HDL_TAP TRUE
J 0
(3050 3375);
DISPLAY 0.872340 (3050 3375);
DISPLAY INVISIBLE (3050 3375);
FORCEPROP 1 LAST PATH I138
J 0
(2723 3500);
DISPLAY 0.872340 (2723 3500);
PAINT GREEN (2723 3500);
DISPLAY INVISIBLE (2723 3500);
FORCEADD TAP..1
(2725 3600);
FORCEPROP 3 LASTPIN (2675 3600) SIG_NAME M_A_CPU0_SA_DQS_DP<3>
J 0
(2685 3610);
DISPLAY 0.659574 (2685 3610);
PAINT MONO (2685 3610);
DISPLAY INVISIBLE (2685 3610);
FORCEPROP 1 LASTPIN (2675 3600) BN 3
J 0
(2663 3608);
DISPLAY 0.680851 (2663 3608);
PAINT GREEN (2663 3608);
FORCEPROP 2 LAST CDS_LIB standard
J 0
(2725 3600);
PAINT MONO (2725 3600);
DISPLAY INVISIBLE (2725 3600);
FORCEPROP 1 LAST BODY_TYPE PLUMBING
J 0
(2725 3650);
DISPLAY 0.872340 (2725 3650);
PAINT GREEN (2725 3650);
DISPLAY INVISIBLE (2725 3650);
FORCEPROP 1 LAST HDL_TAP TRUE
J 0
(3050 3475);
DISPLAY 0.872340 (3050 3475);
DISPLAY INVISIBLE (3050 3475);
FORCEPROP 1 LAST PATH I139
J 0
(2723 3600);
DISPLAY 0.872340 (2723 3600);
PAINT GREEN (2723 3600);
DISPLAY INVISIBLE (2723 3600);
FORCEADD OFFPAGE..1
(-2575 2900);
FORCEPROP 2 LAST $XR0 20 
J 0
(-2826 2900);
DISPLAY 0.638298 (-2826 2900);
PAINT MONO (-2826 2900);
FORCEPROP 2 LAST CDS_LIB standard
J 0
(-2575 2900);
PAINT MONO (-2575 2900);
DISPLAY INVISIBLE (-2575 2900);
FORCEPROP 1 LAST OFFPAGE TRUE
J 0
(-2250 2775);
DISPLAY 0.872340 (-2250 2775);
DISPLAY INVISIBLE (-2250 2775);
FORCEPROP 1 LAST COMMENT_BODY TRUE
J 0
(-2450 2800);
DISPLAY 0.872340 (-2450 2800);
PAINT GREEN (-2450 2800);
DISPLAY INVISIBLE (-2450 2800);
FORCEPROP 2 LAST PATH I14
J 0
(-2525 2975);
DISPLAY 1.021277 (-2525 2975);
DISPLAY INVISIBLE (-2525 2975);
FORCEADD TAP..1
(2725 3700);
FORCEPROP 3 LASTPIN (2675 3700) SIG_NAME M_A_CPU0_SA_DQS_DP<4>
J 0
(2685 3710);
DISPLAY 0.659574 (2685 3710);
PAINT MONO (2685 3710);
DISPLAY INVISIBLE (2685 3710);
FORCEPROP 1 LASTPIN (2675 3700) BN 4
J 0
(2663 3708);
DISPLAY 0.680851 (2663 3708);
PAINT GREEN (2663 3708);
FORCEPROP 2 LAST CDS_LIB standard
J 0
(2725 3700);
PAINT MONO (2725 3700);
DISPLAY INVISIBLE (2725 3700);
FORCEPROP 1 LAST BODY_TYPE PLUMBING
J 0
(2725 3750);
DISPLAY 0.872340 (2725 3750);
PAINT GREEN (2725 3750);
DISPLAY INVISIBLE (2725 3750);
FORCEPROP 1 LAST HDL_TAP TRUE
J 0
(3050 3575);
DISPLAY 0.872340 (3050 3575);
DISPLAY INVISIBLE (3050 3575);
FORCEPROP 1 LAST PATH I140
J 0
(2723 3700);
DISPLAY 0.872340 (2723 3700);
PAINT GREEN (2723 3700);
DISPLAY INVISIBLE (2723 3700);
FORCEADD TAP..1
(2725 3800);
FORCEPROP 3 LASTPIN (2675 3800) SIG_NAME M_A_CPU0_SA_DQS_DP<5>
J 0
(2685 3810);
DISPLAY 0.659574 (2685 3810);
PAINT MONO (2685 3810);
DISPLAY INVISIBLE (2685 3810);
FORCEPROP 1 LASTPIN (2675 3800) BN 5
J 0
(2663 3808);
DISPLAY 0.680851 (2663 3808);
PAINT GREEN (2663 3808);
FORCEPROP 2 LAST CDS_LIB standard
J 0
(2725 3800);
DISPLAY INVISIBLE (2725 3800);
FORCEPROP 1 LAST BODY_TYPE PLUMBING
J 0
(2725 3850);
DISPLAY 0.872340 (2725 3850);
PAINT GREEN (2725 3850);
DISPLAY INVISIBLE (2725 3850);
FORCEPROP 1 LAST HDL_TAP TRUE
J 0
(3050 3675);
DISPLAY 0.872340 (3050 3675);
DISPLAY INVISIBLE (3050 3675);
FORCEPROP 1 LAST PATH I141
J 0
(2723 3800);
DISPLAY 0.872340 (2723 3800);
PAINT GREEN (2723 3800);
DISPLAY INVISIBLE (2723 3800);
FORCEADD TAP..1
(2725 3900);
FORCEPROP 3 LASTPIN (2675 3900) SIG_NAME M_A_CPU0_SA_DQS_DP<6>
J 0
(2685 3910);
DISPLAY 0.659574 (2685 3910);
PAINT MONO (2685 3910);
DISPLAY INVISIBLE (2685 3910);
FORCEPROP 1 LASTPIN (2675 3900) BN 6
J 0
(2663 3908);
DISPLAY 0.680851 (2663 3908);
PAINT GREEN (2663 3908);
FORCEPROP 2 LAST CDS_LIB standard
J 0
(2725 3900);
DISPLAY INVISIBLE (2725 3900);
FORCEPROP 1 LAST BODY_TYPE PLUMBING
J 0
(2725 3950);
DISPLAY 0.872340 (2725 3950);
PAINT GREEN (2725 3950);
DISPLAY INVISIBLE (2725 3950);
FORCEPROP 1 LAST HDL_TAP TRUE
J 0
(3050 3775);
DISPLAY 0.872340 (3050 3775);
DISPLAY INVISIBLE (3050 3775);
FORCEPROP 1 LAST PATH I142
J 0
(2723 3900);
DISPLAY 0.872340 (2723 3900);
PAINT GREEN (2723 3900);
DISPLAY INVISIBLE (2723 3900);
FORCEADD UNIVERSAL_GND..1
(3350 -50);
FORCEPROP 3 LASTPIN (3350 0) SIG_NAME GND\g
J 0
(3360 10);
DISPLAY 0.659574 (3360 10);
PAINT MONO (3360 10);
DISPLAY INVISIBLE (3360 10);
FORCEPROP 2 LAST CDS_LIB logical_power
J 0
(3350 -50);
PAINT MONO (3350 -50);
DISPLAY INVISIBLE (3350 -50);
FORCEPROP 1 LAST HDL_POWER GND
J 1
(3375 -125);
DISPLAY 0.872340 (3375 -125);
PAINT GREEN (3375 -125);
DISPLAY INVISIBLE (3375 -125);
FORCEPROP 1 LAST PATH I143
J 0
(3425 -50);
DISPLAY 0.872340 (3425 -50);
PAINT AQUA (3425 -50);
DISPLAY INVISIBLE (3425 -50);
FORCEADD Q_CAP..1
(3350 325);
FORCEPROP 1 LAST PART_NUMBER CH6103KEA00
J 0
(3400 175);
DISPLAY 0.978723 (3400 175);
DISPLAY INVISIBLE (3400 175);
FORCEPROP 1 LAST MATERIAL X6S
J 0
(3400 225);
DISPLAY 0.978723 (3400 225);
FORCEPROP 1 LAST TOLERANCE 10%
J 0
(3400 275);
DISPLAY 0.978723 (3400 275);
FORCEPROP 1 LAST VALUE 10UF
J 0
(3400 375);
DISPLAY 0.978723 (3400 375);
FORCEPROP 1 LAST PACK_TYPE C0805
J 0
(3400 125);
DISPLAY 0.978723 (3400 125);
FORCEPROP 1 LAST VOLTAGE 16V
J 0
(3400 325);
DISPLAY 0.978723 (3400 325);
FORCEPROP 1 LAST $LOCATION C7
J 0
(3400 425);
DISPLAY 0.978723 (3400 425);
FORCEPROP 1 LASTPIN (3350 425) $PN 1
J 0
(3360 405);
DISPLAY 0.787234 (3360 405);
FORCEPROP 1 LASTPIN (3350 225) $PN 2
J 0
(3360 205);
DISPLAY 0.787234 (3360 205);
FORCEPROP 2 LAST CDS_LIB pure_quanta
J 0
(3350 325);
PAINT MONO (3350 325);
DISPLAY INVISIBLE (3350 325);
FORCEPROP 2 LAST CDS_LOCATION C7
J 0
(3400 525);
DISPLAY 1.021277 (3400 525);
DISPLAY INVISIBLE (3400 525);
FORCEPROP 2 LAST $SEC 1
J 0
(3400 525);
DISPLAY 0.680851 (3400 525);
PAINT MONO (3400 525);
DISPLAY INVISIBLE (3400 525);
FORCEPROP 2 LAST CDS_SEC 1
J 0
(3400 525);
DISPLAY 1.021277 (3400 525);
DISPLAY INVISIBLE (3400 525);
FORCEPROP 1 LAST PATH I144
J 0
(3400 475);
DISPLAY 0.978723 (3400 475);
PAINT WHITE (3400 475);
DISPLAY INVISIBLE (3400 475);
FORCEADD UNIVERSAL_GND..1
(4350 500);
FORCEPROP 3 LASTPIN (4350 550) SIG_NAME GND\g
J 0
(4360 560);
DISPLAY 0.659574 (4360 560);
PAINT MONO (4360 560);
DISPLAY INVISIBLE (4360 560);
FORCEPROP 2 LAST CDS_LIB logical_power
J 0
(4350 500);
PAINT MONO (4350 500);
DISPLAY INVISIBLE (4350 500);
FORCEPROP 1 LAST HDL_POWER GND
J 1
(4375 425);
DISPLAY 0.872340 (4375 425);
PAINT GREEN (4375 425);
DISPLAY INVISIBLE (4375 425);
FORCEPROP 1 LAST PATH I145
J 0
(4425 500);
DISPLAY 0.872340 (4425 500);
PAINT AQUA (4425 500);
DISPLAY INVISIBLE (4425 500);
FORCEADD TAP..1
(2900 2200);
FORCEPROP 3 LASTPIN (2850 2200) SIG_NAME M_A_CPU0_SB_DQS_DN<0>
J 0
(2860 2210);
DISPLAY 0.659574 (2860 2210);
PAINT MONO (2860 2210);
DISPLAY INVISIBLE (2860 2210);
FORCEPROP 1 LASTPIN (2850 2200) BN 0
J 0
(2838 2208);
DISPLAY 0.680851 (2838 2208);
PAINT GREEN (2838 2208);
FORCEPROP 2 LAST CDS_LIB standard
J 0
(2900 2200);
PAINT MONO (2900 2200);
DISPLAY INVISIBLE (2900 2200);
FORCEPROP 1 LAST BODY_TYPE PLUMBING
J 0
(2900 2250);
DISPLAY 0.872340 (2900 2250);
PAINT GREEN (2900 2250);
DISPLAY INVISIBLE (2900 2250);
FORCEPROP 1 LAST HDL_TAP TRUE
J 0
(3225 2075);
DISPLAY 0.872340 (3225 2075);
DISPLAY INVISIBLE (3225 2075);
FORCEPROP 1 LAST PATH I147
J 0
(2898 2200);
DISPLAY 0.872340 (2898 2200);
PAINT GREEN (2898 2200);
DISPLAY INVISIBLE (2898 2200);
FORCEADD TAP..1
(2900 2300);
FORCEPROP 3 LASTPIN (2850 2300) SIG_NAME M_A_CPU0_SB_DQS_DN<1>
J 0
(2860 2310);
DISPLAY 0.659574 (2860 2310);
PAINT MONO (2860 2310);
DISPLAY INVISIBLE (2860 2310);
FORCEPROP 1 LASTPIN (2850 2300) BN 1
J 0
(2838 2308);
DISPLAY 0.680851 (2838 2308);
PAINT GREEN (2838 2308);
FORCEPROP 2 LAST CDS_LIB standard
J 0
(2900 2300);
DISPLAY INVISIBLE (2900 2300);
FORCEPROP 1 LAST BODY_TYPE PLUMBING
J 0
(2900 2350);
DISPLAY 0.872340 (2900 2350);
PAINT GREEN (2900 2350);
DISPLAY INVISIBLE (2900 2350);
FORCEPROP 1 LAST HDL_TAP TRUE
J 0
(3225 2175);
DISPLAY 0.872340 (3225 2175);
DISPLAY INVISIBLE (3225 2175);
FORCEPROP 1 LAST PATH I148
J 0
(2898 2300);
DISPLAY 0.872340 (2898 2300);
PAINT GREEN (2898 2300);
DISPLAY INVISIBLE (2898 2300);
FORCEADD TAP..1
(2900 2400);
FORCEPROP 3 LASTPIN (2850 2400) SIG_NAME M_A_CPU0_SB_DQS_DN<2>
J 0
(2860 2410);
DISPLAY 0.659574 (2860 2410);
PAINT MONO (2860 2410);
DISPLAY INVISIBLE (2860 2410);
FORCEPROP 1 LASTPIN (2850 2400) BN 2
J 0
(2838 2408);
DISPLAY 0.680851 (2838 2408);
PAINT GREEN (2838 2408);
FORCEPROP 2 LAST CDS_LIB standard
J 0
(2900 2400);
DISPLAY INVISIBLE (2900 2400);
FORCEPROP 1 LAST BODY_TYPE PLUMBING
J 0
(2900 2450);
DISPLAY 0.872340 (2900 2450);
PAINT GREEN (2900 2450);
DISPLAY INVISIBLE (2900 2450);
FORCEPROP 1 LAST HDL_TAP TRUE
J 0
(3225 2275);
DISPLAY 0.872340 (3225 2275);
DISPLAY INVISIBLE (3225 2275);
FORCEPROP 1 LAST PATH I149
J 0
(2898 2400);
DISPLAY 0.872340 (2898 2400);
PAINT GREEN (2898 2400);
DISPLAY INVISIBLE (2898 2400);
FORCEADD OFFPAGE..3
R 2
(-2575 2825);
FORCEPROP 2 LAST $XR1 82 
J 0
(-2944 2825);
DISPLAY 0.638298 (-2944 2825);
PAINT MONO (-2944 2825);
FORCEPROP 2 LAST $XR0 20 
J 0
(-2854 2825);
DISPLAY 0.638298 (-2854 2825);
PAINT MONO (-2854 2825);
FORCEPROP 2 LAST CDS_LIB standard
J 0
(-2575 2825);
PAINT MONO (-2575 2825);
DISPLAY INVISIBLE (-2575 2825);
FORCEPROP 1 LAST OFFPAGE TRUE
J 2
(-2900 2700);
DISPLAY 0.872340 (-2900 2700);
DISPLAY INVISIBLE (-2900 2700);
FORCEPROP 1 LAST COMMENT_BODY TRUE
J 2
(-2525 2725);
DISPLAY 0.872340 (-2525 2725);
PAINT GREEN (-2525 2725);
DISPLAY INVISIBLE (-2525 2725);
FORCEPROP 2 LAST PATH I15
J 0
(-2525 2900);
DISPLAY 1.021277 (-2525 2900);
DISPLAY INVISIBLE (-2525 2900);
FORCEADD TAP..1
(2900 2500);
FORCEPROP 3 LASTPIN (2850 2500) SIG_NAME M_A_CPU0_SB_DQS_DN<3>
J 0
(2860 2510);
DISPLAY 0.659574 (2860 2510);
PAINT MONO (2860 2510);
DISPLAY INVISIBLE (2860 2510);
FORCEPROP 1 LASTPIN (2850 2500) BN 3
J 0
(2838 2508);
DISPLAY 0.680851 (2838 2508);
PAINT GREEN (2838 2508);
FORCEPROP 2 LAST CDS_LIB standard
J 0
(2900 2500);
PAINT MONO (2900 2500);
DISPLAY INVISIBLE (2900 2500);
FORCEPROP 1 LAST BODY_TYPE PLUMBING
J 0
(2900 2550);
DISPLAY 0.872340 (2900 2550);
PAINT GREEN (2900 2550);
DISPLAY INVISIBLE (2900 2550);
FORCEPROP 1 LAST HDL_TAP TRUE
J 0
(3225 2375);
DISPLAY 0.872340 (3225 2375);
DISPLAY INVISIBLE (3225 2375);
FORCEPROP 1 LAST PATH I150
J 0
(2898 2500);
DISPLAY 0.872340 (2898 2500);
PAINT GREEN (2898 2500);
DISPLAY INVISIBLE (2898 2500);
FORCEADD TAP..1
(2900 2700);
FORCEPROP 3 LASTPIN (2850 2700) SIG_NAME M_A_CPU0_SB_DQS_DN<5>
J 0
(2860 2710);
DISPLAY 0.659574 (2860 2710);
PAINT MONO (2860 2710);
DISPLAY INVISIBLE (2860 2710);
FORCEPROP 1 LASTPIN (2850 2700) BN 5
J 0
(2838 2708);
DISPLAY 0.680851 (2838 2708);
PAINT GREEN (2838 2708);
FORCEPROP 2 LAST CDS_LIB standard
J 0
(2900 2700);
DISPLAY INVISIBLE (2900 2700);
FORCEPROP 1 LAST BODY_TYPE PLUMBING
J 0
(2900 2750);
DISPLAY 0.872340 (2900 2750);
PAINT GREEN (2900 2750);
DISPLAY INVISIBLE (2900 2750);
FORCEPROP 1 LAST HDL_TAP TRUE
J 0
(3225 2575);
DISPLAY 0.872340 (3225 2575);
DISPLAY INVISIBLE (3225 2575);
FORCEPROP 1 LAST PATH I151
J 0
(2898 2700);
DISPLAY 0.872340 (2898 2700);
PAINT GREEN (2898 2700);
DISPLAY INVISIBLE (2898 2700);
FORCEADD TAP..1
(2900 2600);
FORCEPROP 3 LASTPIN (2850 2600) SIG_NAME M_A_CPU0_SB_DQS_DN<4>
J 0
(2860 2610);
DISPLAY 0.659574 (2860 2610);
PAINT MONO (2860 2610);
DISPLAY INVISIBLE (2860 2610);
FORCEPROP 1 LASTPIN (2850 2600) BN 4
J 0
(2838 2608);
DISPLAY 0.680851 (2838 2608);
PAINT GREEN (2838 2608);
FORCEPROP 2 LAST CDS_LIB standard
J 0
(2900 2600);
PAINT MONO (2900 2600);
DISPLAY INVISIBLE (2900 2600);
FORCEPROP 1 LAST BODY_TYPE PLUMBING
J 0
(2900 2650);
DISPLAY 0.872340 (2900 2650);
PAINT GREEN (2900 2650);
DISPLAY INVISIBLE (2900 2650);
FORCEPROP 1 LAST HDL_TAP TRUE
J 0
(3225 2475);
DISPLAY 0.872340 (3225 2475);
DISPLAY INVISIBLE (3225 2475);
FORCEPROP 1 LAST PATH I152
J 0
(2898 2600);
DISPLAY 0.872340 (2898 2600);
PAINT GREEN (2898 2600);
DISPLAY INVISIBLE (2898 2600);
FORCEADD TAP..1
(2900 2800);
FORCEPROP 3 LASTPIN (2850 2800) SIG_NAME M_A_CPU0_SB_DQS_DN<6>
J 0
(2860 2810);
DISPLAY 0.659574 (2860 2810);
PAINT MONO (2860 2810);
DISPLAY INVISIBLE (2860 2810);
FORCEPROP 1 LASTPIN (2850 2800) BN 6
J 0
(2838 2808);
DISPLAY 0.680851 (2838 2808);
PAINT GREEN (2838 2808);
FORCEPROP 2 LAST CDS_LIB standard
J 0
(2900 2800);
DISPLAY INVISIBLE (2900 2800);
FORCEPROP 1 LAST BODY_TYPE PLUMBING
J 0
(2900 2850);
DISPLAY 0.872340 (2900 2850);
PAINT GREEN (2900 2850);
DISPLAY INVISIBLE (2900 2850);
FORCEPROP 1 LAST HDL_TAP TRUE
J 0
(3225 2675);
DISPLAY 0.872340 (3225 2675);
DISPLAY INVISIBLE (3225 2675);
FORCEPROP 1 LAST PATH I153
J 0
(2898 2800);
DISPLAY 0.872340 (2898 2800);
PAINT GREEN (2898 2800);
DISPLAY INVISIBLE (2898 2800);
FORCEADD TAP..1
(2900 2900);
FORCEPROP 3 LASTPIN (2850 2900) SIG_NAME M_A_CPU0_SB_DQS_DN<7>
J 0
(2860 2910);
DISPLAY 0.659574 (2860 2910);
PAINT MONO (2860 2910);
DISPLAY INVISIBLE (2860 2910);
FORCEPROP 1 LASTPIN (2850 2900) BN 7
J 0
(2838 2908);
DISPLAY 0.680851 (2838 2908);
PAINT GREEN (2838 2908);
FORCEPROP 2 LAST CDS_LIB standard
J 0
(2900 2900);
DISPLAY INVISIBLE (2900 2900);
FORCEPROP 1 LAST BODY_TYPE PLUMBING
J 0
(2900 2950);
DISPLAY 0.872340 (2900 2950);
PAINT GREEN (2900 2950);
DISPLAY INVISIBLE (2900 2950);
FORCEPROP 1 LAST HDL_TAP TRUE
J 0
(3225 2775);
DISPLAY 0.872340 (3225 2775);
DISPLAY INVISIBLE (3225 2775);
FORCEPROP 1 LAST PATH I154
J 0
(2898 2900);
DISPLAY 0.872340 (2898 2900);
PAINT GREEN (2898 2900);
DISPLAY INVISIBLE (2898 2900);
FORCEADD TAP..1
(2900 3000);
FORCEPROP 3 LASTPIN (2850 3000) SIG_NAME M_A_CPU0_SB_DQS_DN<8>
J 0
(2860 3010);
DISPLAY 0.659574 (2860 3010);
PAINT MONO (2860 3010);
DISPLAY INVISIBLE (2860 3010);
FORCEPROP 1 LASTPIN (2850 3000) BN 8
J 0
(2838 3008);
DISPLAY 0.680851 (2838 3008);
PAINT GREEN (2838 3008);
FORCEPROP 2 LAST CDS_LIB standard
J 0
(2900 3000);
DISPLAY INVISIBLE (2900 3000);
FORCEPROP 1 LAST BODY_TYPE PLUMBING
J 0
(2900 3050);
DISPLAY 0.872340 (2900 3050);
PAINT GREEN (2900 3050);
DISPLAY INVISIBLE (2900 3050);
FORCEPROP 1 LAST HDL_TAP TRUE
J 0
(3225 2875);
DISPLAY 0.872340 (3225 2875);
DISPLAY INVISIBLE (3225 2875);
FORCEPROP 1 LAST PATH I155
J 0
(2898 3000);
DISPLAY 0.872340 (2898 3000);
PAINT GREEN (2898 3000);
DISPLAY INVISIBLE (2898 3000);
FORCEADD TAP..1
(2900 3100);
FORCEPROP 3 LASTPIN (2850 3100) SIG_NAME M_A_CPU0_SB_DQS_DN<9>
J 0
(2860 3110);
DISPLAY 0.659574 (2860 3110);
PAINT MONO (2860 3110);
DISPLAY INVISIBLE (2860 3110);
FORCEPROP 1 LASTPIN (2850 3100) BN 9
J 0
(2838 3108);
DISPLAY 0.680851 (2838 3108);
PAINT GREEN (2838 3108);
FORCEPROP 2 LAST CDS_LIB standard
J 0
(2900 3100);
DISPLAY INVISIBLE (2900 3100);
FORCEPROP 1 LAST BODY_TYPE PLUMBING
J 0
(2900 3150);
DISPLAY 0.872340 (2900 3150);
PAINT GREEN (2900 3150);
DISPLAY INVISIBLE (2900 3150);
FORCEPROP 1 LAST HDL_TAP TRUE
J 0
(3225 2975);
DISPLAY 0.872340 (3225 2975);
DISPLAY INVISIBLE (3225 2975);
FORCEPROP 1 LAST PATH I156
J 0
(2898 3100);
DISPLAY 0.872340 (2898 3100);
PAINT GREEN (2898 3100);
DISPLAY INVISIBLE (2898 3100);
FORCEADD TAP..1
(2900 3250);
FORCEPROP 3 LASTPIN (2850 3250) SIG_NAME M_A_CPU0_SA_DQS_DN<0>
J 0
(2860 3260);
DISPLAY 0.659574 (2860 3260);
PAINT MONO (2860 3260);
DISPLAY INVISIBLE (2860 3260);
FORCEPROP 1 LASTPIN (2850 3250) BN 0
J 0
(2838 3258);
DISPLAY 0.680851 (2838 3258);
PAINT GREEN (2838 3258);
FORCEPROP 2 LAST CDS_LIB standard
J 0
(2900 3250);
PAINT MONO (2900 3250);
DISPLAY INVISIBLE (2900 3250);
FORCEPROP 1 LAST BODY_TYPE PLUMBING
J 0
(2900 3300);
DISPLAY 0.872340 (2900 3300);
PAINT GREEN (2900 3300);
DISPLAY INVISIBLE (2900 3300);
FORCEPROP 1 LAST HDL_TAP TRUE
J 0
(3225 3125);
DISPLAY 0.872340 (3225 3125);
DISPLAY INVISIBLE (3225 3125);
FORCEPROP 1 LAST PATH I157
J 0
(2898 3250);
DISPLAY 0.872340 (2898 3250);
PAINT GREEN (2898 3250);
DISPLAY INVISIBLE (2898 3250);
FORCEADD TAP..1
(2900 3350);
FORCEPROP 3 LASTPIN (2850 3350) SIG_NAME M_A_CPU0_SA_DQS_DN<1>
J 0
(2860 3360);
DISPLAY 0.659574 (2860 3360);
PAINT MONO (2860 3360);
DISPLAY INVISIBLE (2860 3360);
FORCEPROP 1 LASTPIN (2850 3350) BN 1
J 0
(2838 3358);
DISPLAY 0.680851 (2838 3358);
PAINT GREEN (2838 3358);
FORCEPROP 2 LAST CDS_LIB standard
J 0
(2900 3350);
DISPLAY INVISIBLE (2900 3350);
FORCEPROP 1 LAST BODY_TYPE PLUMBING
J 0
(2900 3400);
DISPLAY 0.872340 (2900 3400);
PAINT GREEN (2900 3400);
DISPLAY INVISIBLE (2900 3400);
FORCEPROP 1 LAST HDL_TAP TRUE
J 0
(3225 3225);
DISPLAY 0.872340 (3225 3225);
DISPLAY INVISIBLE (3225 3225);
FORCEPROP 1 LAST PATH I158
J 0
(2898 3350);
DISPLAY 0.872340 (2898 3350);
PAINT GREEN (2898 3350);
DISPLAY INVISIBLE (2898 3350);
FORCEADD TAP..1
(2900 3450);
FORCEPROP 3 LASTPIN (2850 3450) SIG_NAME M_A_CPU0_SA_DQS_DN<2>
J 0
(2860 3460);
DISPLAY 0.659574 (2860 3460);
PAINT MONO (2860 3460);
DISPLAY INVISIBLE (2860 3460);
FORCEPROP 1 LASTPIN (2850 3450) BN 2
J 0
(2838 3458);
DISPLAY 0.680851 (2838 3458);
PAINT GREEN (2838 3458);
FORCEPROP 2 LAST CDS_LIB standard
J 0
(2900 3450);
DISPLAY INVISIBLE (2900 3450);
FORCEPROP 1 LAST BODY_TYPE PLUMBING
J 0
(2900 3500);
DISPLAY 0.872340 (2900 3500);
PAINT GREEN (2900 3500);
DISPLAY INVISIBLE (2900 3500);
FORCEPROP 1 LAST HDL_TAP TRUE
J 0
(3225 3325);
DISPLAY 0.872340 (3225 3325);
DISPLAY INVISIBLE (3225 3325);
FORCEPROP 1 LAST PATH I159
J 0
(2898 3450);
DISPLAY 0.872340 (2898 3450);
PAINT GREEN (2898 3450);
DISPLAY INVISIBLE (2898 3450);
FORCEADD OFFPAGE..1
(-2575 2950);
FORCEPROP 2 LAST $XR0 20 
J 0
(-2826 2950);
DISPLAY 0.638298 (-2826 2950);
PAINT MONO (-2826 2950);
FORCEPROP 2 LAST CDS_LIB standard
J 0
(-2575 2950);
PAINT MONO (-2575 2950);
DISPLAY INVISIBLE (-2575 2950);
FORCEPROP 1 LAST OFFPAGE TRUE
J 0
(-2250 2825);
DISPLAY 0.872340 (-2250 2825);
DISPLAY INVISIBLE (-2250 2825);
FORCEPROP 1 LAST COMMENT_BODY TRUE
J 0
(-2450 2850);
DISPLAY 0.872340 (-2450 2850);
PAINT GREEN (-2450 2850);
DISPLAY INVISIBLE (-2450 2850);
FORCEPROP 2 LAST PATH I16
J 0
(-2525 3025);
DISPLAY 1.021277 (-2525 3025);
DISPLAY INVISIBLE (-2525 3025);
FORCEADD TAP..1
(2900 3550);
FORCEPROP 3 LASTPIN (2850 3550) SIG_NAME M_A_CPU0_SA_DQS_DN<3>
J 0
(2860 3560);
DISPLAY 0.659574 (2860 3560);
PAINT MONO (2860 3560);
DISPLAY INVISIBLE (2860 3560);
FORCEPROP 1 LASTPIN (2850 3550) BN 3
J 0
(2838 3558);
DISPLAY 0.680851 (2838 3558);
PAINT GREEN (2838 3558);
FORCEPROP 2 LAST CDS_LIB standard
J 0
(2900 3550);
PAINT MONO (2900 3550);
DISPLAY INVISIBLE (2900 3550);
FORCEPROP 1 LAST BODY_TYPE PLUMBING
J 0
(2900 3600);
DISPLAY 0.872340 (2900 3600);
PAINT GREEN (2900 3600);
DISPLAY INVISIBLE (2900 3600);
FORCEPROP 1 LAST HDL_TAP TRUE
J 0
(3225 3425);
DISPLAY 0.872340 (3225 3425);
DISPLAY INVISIBLE (3225 3425);
FORCEPROP 1 LAST PATH I160
J 0
(2898 3550);
DISPLAY 0.872340 (2898 3550);
PAINT GREEN (2898 3550);
DISPLAY INVISIBLE (2898 3550);
FORCEADD TAP..1
(2900 3650);
FORCEPROP 3 LASTPIN (2850 3650) SIG_NAME M_A_CPU0_SA_DQS_DN<4>
J 0
(2860 3660);
DISPLAY 0.659574 (2860 3660);
PAINT MONO (2860 3660);
DISPLAY INVISIBLE (2860 3660);
FORCEPROP 1 LASTPIN (2850 3650) BN 4
J 0
(2838 3658);
DISPLAY 0.680851 (2838 3658);
PAINT GREEN (2838 3658);
FORCEPROP 2 LAST CDS_LIB standard
J 0
(2900 3650);
PAINT MONO (2900 3650);
DISPLAY INVISIBLE (2900 3650);
FORCEPROP 1 LAST BODY_TYPE PLUMBING
J 0
(2900 3700);
DISPLAY 0.872340 (2900 3700);
PAINT GREEN (2900 3700);
DISPLAY INVISIBLE (2900 3700);
FORCEPROP 1 LAST HDL_TAP TRUE
J 0
(3225 3525);
DISPLAY 0.872340 (3225 3525);
DISPLAY INVISIBLE (3225 3525);
FORCEPROP 1 LAST PATH I161
J 0
(2898 3650);
DISPLAY 0.872340 (2898 3650);
PAINT GREEN (2898 3650);
DISPLAY INVISIBLE (2898 3650);
FORCEADD TAP..1
(2900 3750);
FORCEPROP 3 LASTPIN (2850 3750) SIG_NAME M_A_CPU0_SA_DQS_DN<5>
J 0
(2860 3760);
DISPLAY 0.659574 (2860 3760);
PAINT MONO (2860 3760);
DISPLAY INVISIBLE (2860 3760);
FORCEPROP 1 LASTPIN (2850 3750) BN 5
J 0
(2838 3758);
DISPLAY 0.680851 (2838 3758);
PAINT GREEN (2838 3758);
FORCEPROP 2 LAST CDS_LIB standard
J 0
(2900 3750);
DISPLAY INVISIBLE (2900 3750);
FORCEPROP 1 LAST BODY_TYPE PLUMBING
J 0
(2900 3800);
DISPLAY 0.872340 (2900 3800);
PAINT GREEN (2900 3800);
DISPLAY INVISIBLE (2900 3800);
FORCEPROP 1 LAST HDL_TAP TRUE
J 0
(3225 3625);
DISPLAY 0.872340 (3225 3625);
DISPLAY INVISIBLE (3225 3625);
FORCEPROP 1 LAST PATH I162
J 0
(2898 3750);
DISPLAY 0.872340 (2898 3750);
PAINT GREEN (2898 3750);
DISPLAY INVISIBLE (2898 3750);
FORCEADD TAP..1
(2900 3850);
FORCEPROP 3 LASTPIN (2850 3850) SIG_NAME M_A_CPU0_SA_DQS_DN<6>
J 0
(2860 3860);
DISPLAY 0.659574 (2860 3860);
PAINT MONO (2860 3860);
DISPLAY INVISIBLE (2860 3860);
FORCEPROP 1 LASTPIN (2850 3850) BN 6
J 0
(2838 3858);
DISPLAY 0.680851 (2838 3858);
PAINT GREEN (2838 3858);
FORCEPROP 2 LAST CDS_LIB standard
J 0
(2900 3850);
DISPLAY INVISIBLE (2900 3850);
FORCEPROP 1 LAST BODY_TYPE PLUMBING
J 0
(2900 3900);
DISPLAY 0.872340 (2900 3900);
PAINT GREEN (2900 3900);
DISPLAY INVISIBLE (2900 3900);
FORCEPROP 1 LAST HDL_TAP TRUE
J 0
(3225 3725);
DISPLAY 0.872340 (3225 3725);
DISPLAY INVISIBLE (3225 3725);
FORCEPROP 1 LAST PATH I163
J 0
(2898 3850);
DISPLAY 0.872340 (2898 3850);
PAINT GREEN (2898 3850);
DISPLAY INVISIBLE (2898 3850);
FORCEADD TAP..1
(2900 3950);
FORCEPROP 3 LASTPIN (2850 3950) SIG_NAME M_A_CPU0_SA_DQS_DN<7>
J 0
(2860 3960);
DISPLAY 0.659574 (2860 3960);
PAINT MONO (2860 3960);
DISPLAY INVISIBLE (2860 3960);
FORCEPROP 1 LASTPIN (2850 3950) BN 7
J 0
(2838 3958);
DISPLAY 0.680851 (2838 3958);
PAINT GREEN (2838 3958);
FORCEPROP 2 LAST CDS_LIB standard
J 0
(2900 3950);
DISPLAY INVISIBLE (2900 3950);
FORCEPROP 1 LAST BODY_TYPE PLUMBING
J 0
(2900 4000);
DISPLAY 0.872340 (2900 4000);
PAINT GREEN (2900 4000);
DISPLAY INVISIBLE (2900 4000);
FORCEPROP 1 LAST HDL_TAP TRUE
J 0
(3225 3825);
DISPLAY 0.872340 (3225 3825);
DISPLAY INVISIBLE (3225 3825);
FORCEPROP 1 LAST PATH I164
J 0
(2898 3950);
DISPLAY 0.872340 (2898 3950);
PAINT GREEN (2898 3950);
DISPLAY INVISIBLE (2898 3950);
FORCEADD OFFPAGE..2
(3850 3125);
FORCEPROP 2 LAST $XR1 82 
J 0
(4129 3125);
DISPLAY 0.638298 (4129 3125);
PAINT MONO (4129 3125);
FORCEPROP 2 LAST $XR0 20 
J 0
(4039 3125);
DISPLAY 0.638298 (4039 3125);
PAINT MONO (4039 3125);
FORCEPROP 2 LAST CDS_LIB standard
J 0
(3850 3125);
PAINT MONO (3850 3125);
DISPLAY INVISIBLE (3850 3125);
FORCEPROP 1 LAST OFFPAGE TRUE
J 0
(4175 3000);
DISPLAY 1.170213 (4175 3000);
PAINT GREEN (4175 3000);
DISPLAY INVISIBLE (4175 3000);
FORCEPROP 1 LAST COMMENT_BODY TRUE
J 0
(3805 3030);
DISPLAY 1.170213 (3805 3030);
PAINT GREEN (3805 3030);
DISPLAY INVISIBLE (3805 3030);
FORCEPROP 2 LAST PATH I165
J 0
(4025 3200);
DISPLAY 1.021277 (4025 3200);
DISPLAY INVISIBLE (4025 3200);
FORCEADD OFFPAGE..2
(3850 3175);
FORCEPROP 2 LAST $XR1 82 
J 0
(4129 3175);
DISPLAY 0.638298 (4129 3175);
PAINT MONO (4129 3175);
FORCEPROP 2 LAST $XR0 20 
J 0
(4039 3175);
DISPLAY 0.638298 (4039 3175);
PAINT MONO (4039 3175);
FORCEPROP 2 LAST CDS_LIB standard
J 0
(3850 3175);
PAINT MONO (3850 3175);
DISPLAY INVISIBLE (3850 3175);
FORCEPROP 1 LAST OFFPAGE TRUE
J 0
(4175 3050);
DISPLAY 1.170213 (4175 3050);
PAINT GREEN (4175 3050);
DISPLAY INVISIBLE (4175 3050);
FORCEPROP 1 LAST COMMENT_BODY TRUE
J 0
(3805 3080);
DISPLAY 1.170213 (3805 3080);
PAINT GREEN (3805 3080);
DISPLAY INVISIBLE (3805 3080);
FORCEPROP 2 LAST PATH I166
J 0
(4025 3250);
DISPLAY 1.021277 (4025 3250);
DISPLAY INVISIBLE (4025 3250);
FORCEADD OFFPAGE..3
(825 4225);
FORCEPROP 2 LAST $XR1 82 
J 0
(1129 4225);
DISPLAY 0.638298 (1129 4225);
PAINT MONO (1129 4225);
FORCEPROP 2 LAST $XR0 20 
J 0
(1039 4225);
DISPLAY 0.638298 (1039 4225);
PAINT MONO (1039 4225);
FORCEPROP 2 LAST CDS_LIB standard
J 2
(825 4225);
DISPLAY INVISIBLE (825 4225);
FORCEPROP 1 LAST OFFPAGE TRUE
J 0
(1150 4100);
DISPLAY 0.872340 (1150 4100);
DISPLAY INVISIBLE (1150 4100);
FORCEPROP 1 LAST COMMENT_BODY TRUE
J 0
(775 4125);
DISPLAY 0.872340 (775 4125);
PAINT GREEN (775 4125);
DISPLAY INVISIBLE (775 4125);
FORCEPROP 2 LAST PATH I167
J 0
(1025 4300);
DISPLAY 1.021277 (1025 4300);
DISPLAY INVISIBLE (1025 4300);
FORCEADD TAP..1
(2725 4000);
FORCEPROP 3 LASTPIN (2675 4000) SIG_NAME M_A_CPU0_SA_DQS_DP<7>
J 0
(2685 4010);
DISPLAY 0.659574 (2685 4010);
PAINT MONO (2685 4010);
DISPLAY INVISIBLE (2685 4010);
FORCEPROP 1 LASTPIN (2675 4000) BN 7
J 0
(2663 4008);
DISPLAY 0.680851 (2663 4008);
PAINT GREEN (2663 4008);
FORCEPROP 2 LAST CDS_LIB standard
J 0
(2725 4000);
DISPLAY INVISIBLE (2725 4000);
FORCEPROP 1 LAST BODY_TYPE PLUMBING
J 0
(2725 4050);
DISPLAY 0.872340 (2725 4050);
PAINT GREEN (2725 4050);
DISPLAY INVISIBLE (2725 4050);
FORCEPROP 1 LAST HDL_TAP TRUE
J 0
(3050 3875);
DISPLAY 0.872340 (3050 3875);
DISPLAY INVISIBLE (3050 3875);
FORCEPROP 1 LAST PATH I168
J 0
(2723 4000);
DISPLAY 0.872340 (2723 4000);
PAINT GREEN (2723 4000);
DISPLAY INVISIBLE (2723 4000);
FORCEADD TAP..1
(2725 4100);
FORCEPROP 3 LASTPIN (2675 4100) SIG_NAME M_A_CPU0_SA_DQS_DP<8>
J 0
(2685 4110);
DISPLAY 0.659574 (2685 4110);
PAINT MONO (2685 4110);
DISPLAY INVISIBLE (2685 4110);
FORCEPROP 1 LASTPIN (2675 4100) BN 8
J 0
(2663 4108);
DISPLAY 0.680851 (2663 4108);
PAINT GREEN (2663 4108);
FORCEPROP 2 LAST CDS_LIB standard
J 0
(2725 4100);
DISPLAY INVISIBLE (2725 4100);
FORCEPROP 1 LAST BODY_TYPE PLUMBING
J 0
(2725 4150);
DISPLAY 0.872340 (2725 4150);
PAINT GREEN (2725 4150);
DISPLAY INVISIBLE (2725 4150);
FORCEPROP 1 LAST HDL_TAP TRUE
J 0
(3050 3975);
DISPLAY 0.872340 (3050 3975);
DISPLAY INVISIBLE (3050 3975);
FORCEPROP 1 LAST PATH I169
J 0
(2723 4100);
DISPLAY 0.872340 (2723 4100);
PAINT GREEN (2723 4100);
DISPLAY INVISIBLE (2723 4100);
FORCEADD OFFPAGE..1
(-2575 3050);
FORCEPROP 2 LAST $XR0 20 
J 0
(-2826 3050);
DISPLAY 0.638298 (-2826 3050);
PAINT MONO (-2826 3050);
FORCEPROP 2 LAST CDS_LIB standard
J 0
(-2575 3050);
PAINT MONO (-2575 3050);
DISPLAY INVISIBLE (-2575 3050);
FORCEPROP 1 LAST OFFPAGE TRUE
J 0
(-2250 2925);
DISPLAY 0.872340 (-2250 2925);
DISPLAY INVISIBLE (-2250 2925);
FORCEPROP 1 LAST COMMENT_BODY TRUE
J 0
(-2450 2950);
DISPLAY 0.872340 (-2450 2950);
PAINT GREEN (-2450 2950);
DISPLAY INVISIBLE (-2450 2950);
FORCEPROP 2 LAST PATH I17
J 0
(-2525 3125);
DISPLAY 1.021277 (-2525 3125);
DISPLAY INVISIBLE (-2525 3125);
FORCEADD TAP..1
(2725 4200);
FORCEPROP 3 LASTPIN (2675 4200) SIG_NAME M_A_CPU0_SA_DQS_DP<9>
J 0
(2685 4210);
DISPLAY 0.659574 (2685 4210);
PAINT MONO (2685 4210);
DISPLAY INVISIBLE (2685 4210);
FORCEPROP 1 LASTPIN (2675 4200) BN 9
J 0
(2663 4208);
DISPLAY 0.680851 (2663 4208);
PAINT GREEN (2663 4208);
FORCEPROP 2 LAST CDS_LIB standard
J 0
(2725 4200);
DISPLAY INVISIBLE (2725 4200);
FORCEPROP 1 LAST BODY_TYPE PLUMBING
J 0
(2725 4250);
DISPLAY 0.872340 (2725 4250);
PAINT GREEN (2725 4250);
DISPLAY INVISIBLE (2725 4250);
FORCEPROP 1 LAST HDL_TAP TRUE
J 0
(3050 4075);
DISPLAY 0.872340 (3050 4075);
DISPLAY INVISIBLE (3050 4075);
FORCEPROP 1 LAST PATH I170
J 0
(2723 4200);
DISPLAY 0.872340 (2723 4200);
PAINT GREEN (2723 4200);
DISPLAY INVISIBLE (2723 4200);
FORCEADD TAP..1
(2900 4050);
FORCEPROP 3 LASTPIN (2850 4050) SIG_NAME M_A_CPU0_SA_DQS_DN<8>
J 0
(2860 4060);
DISPLAY 0.659574 (2860 4060);
PAINT MONO (2860 4060);
DISPLAY INVISIBLE (2860 4060);
FORCEPROP 1 LASTPIN (2850 4050) BN 8
J 0
(2838 4058);
DISPLAY 0.680851 (2838 4058);
PAINT GREEN (2838 4058);
FORCEPROP 2 LAST CDS_LIB standard
J 0
(2900 4050);
DISPLAY INVISIBLE (2900 4050);
FORCEPROP 1 LAST BODY_TYPE PLUMBING
J 0
(2900 4100);
DISPLAY 0.872340 (2900 4100);
PAINT GREEN (2900 4100);
DISPLAY INVISIBLE (2900 4100);
FORCEPROP 1 LAST HDL_TAP TRUE
J 0
(3225 3925);
DISPLAY 0.872340 (3225 3925);
DISPLAY INVISIBLE (3225 3925);
FORCEPROP 1 LAST PATH I171
J 0
(2898 4050);
DISPLAY 0.872340 (2898 4050);
PAINT GREEN (2898 4050);
DISPLAY INVISIBLE (2898 4050);
FORCEADD TAP..1
(2900 4150);
FORCEPROP 3 LASTPIN (2850 4150) SIG_NAME M_A_CPU0_SA_DQS_DN<9>
J 0
(2860 4160);
DISPLAY 0.659574 (2860 4160);
PAINT MONO (2860 4160);
DISPLAY INVISIBLE (2860 4160);
FORCEPROP 1 LASTPIN (2850 4150) BN 9
J 0
(2838 4158);
DISPLAY 0.680851 (2838 4158);
PAINT GREEN (2838 4158);
FORCEPROP 2 LAST CDS_LIB standard
J 0
(2900 4150);
DISPLAY INVISIBLE (2900 4150);
FORCEPROP 1 LAST BODY_TYPE PLUMBING
J 0
(2900 4200);
DISPLAY 0.872340 (2900 4200);
PAINT GREEN (2900 4200);
DISPLAY INVISIBLE (2900 4200);
FORCEPROP 1 LAST HDL_TAP TRUE
J 0
(3225 4025);
DISPLAY 0.872340 (3225 4025);
DISPLAY INVISIBLE (3225 4025);
FORCEPROP 1 LAST PATH I172
J 0
(2898 4150);
DISPLAY 0.872340 (2898 4150);
PAINT GREEN (2898 4150);
DISPLAY INVISIBLE (2898 4150);
FORCEADD OFFPAGE..2
(3850 4175);
FORCEPROP 2 LAST $XR1 82 
J 0
(4129 4175);
DISPLAY 0.638298 (4129 4175);
PAINT MONO (4129 4175);
FORCEPROP 2 LAST $XR0 20 
J 0
(4039 4175);
DISPLAY 0.638298 (4039 4175);
PAINT MONO (4039 4175);
FORCEPROP 2 LAST CDS_LIB standard
J 0
(3850 4175);
PAINT MONO (3850 4175);
DISPLAY INVISIBLE (3850 4175);
FORCEPROP 1 LAST OFFPAGE TRUE
J 0
(4175 4050);
DISPLAY 1.170213 (4175 4050);
PAINT GREEN (4175 4050);
DISPLAY INVISIBLE (4175 4050);
FORCEPROP 1 LAST COMMENT_BODY TRUE
J 0
(3805 4080);
DISPLAY 1.170213 (3805 4080);
PAINT GREEN (3805 4080);
DISPLAY INVISIBLE (3805 4080);
FORCEPROP 2 LAST PATH I173
J 0
(4025 4250);
DISPLAY 1.021277 (4025 4250);
DISPLAY INVISIBLE (4025 4250);
FORCEADD OFFPAGE..2
(3850 4225);
FORCEPROP 2 LAST $XR1 82 
J 0
(4129 4225);
DISPLAY 0.638298 (4129 4225);
PAINT MONO (4129 4225);
FORCEPROP 2 LAST $XR0 20 
J 0
(4039 4225);
DISPLAY 0.638298 (4039 4225);
PAINT MONO (4039 4225);
FORCEPROP 2 LAST CDS_LIB standard
J 0
(3850 4225);
PAINT MONO (3850 4225);
DISPLAY INVISIBLE (3850 4225);
FORCEPROP 1 LAST OFFPAGE TRUE
J 0
(4175 4100);
DISPLAY 1.170213 (4175 4100);
PAINT GREEN (4175 4100);
DISPLAY INVISIBLE (4175 4100);
FORCEPROP 1 LAST COMMENT_BODY TRUE
J 0
(3805 4130);
DISPLAY 1.170213 (3805 4130);
PAINT GREEN (3805 4130);
DISPLAY INVISIBLE (3805 4130);
FORCEPROP 2 LAST PATH I174
J 0
(4025 4300);
DISPLAY 1.021277 (4025 4300);
DISPLAY INVISIBLE (4025 4300);
FORCEADD VCC_CORE..1
(4350 4750);
FORCEPROP 3 LASTPIN (4350 4700) SIG_NAME P12V_S3_AUX_CPU0_NVDIMM\g
J 0
(4360 4710);
DISPLAY 0.659574 (4360 4710);
PAINT MONO (4360 4710);
DISPLAY INVISIBLE (4360 4710);
FORCEPROP 1 LAST HDL_POWER P12V_S3_AUX_CPU0_NVDIMM
J 1
(4350 4800);
DISPLAY 1.148936 (4350 4800);
PAINT GREEN (4350 4800);
FORCEPROP 2 LAST CDS_LIB logical_power
J 0
(4350 4750);
PAINT MONO (4350 4750);
DISPLAY INVISIBLE (4350 4750);
FORCEPROP 1 LAST PATH I175
J 0
(4400 4775);
DISPLAY 0.872340 (4400 4775);
PAINT AQUA (4400 4775);
DISPLAY INVISIBLE (4400 4775);
FORCEADD UNIVERSAL_GND..1
(6050 500);
FORCEPROP 3 LASTPIN (6050 550) SIG_NAME GND\g
J 0
(6060 560);
DISPLAY 0.659574 (6060 560);
PAINT MONO (6060 560);
DISPLAY INVISIBLE (6060 560);
FORCEPROP 2 LAST CDS_LIB logical_power
J 0
(6050 500);
PAINT MONO (6050 500);
DISPLAY INVISIBLE (6050 500);
FORCEPROP 1 LAST HDL_POWER GND
J 1
(6075 425);
DISPLAY 0.872340 (6075 425);
PAINT GREEN (6075 425);
DISPLAY INVISIBLE (6075 425);
FORCEPROP 1 LAST PATH I176
J 0
(6125 500);
DISPLAY 0.872340 (6125 500);
PAINT AQUA (6125 500);
DISPLAY INVISIBLE (6125 500);
FORCEADD SCONN288_ADR50017P087CC..1
(-825 2475);
FORCEPROP 1 LAST PART_NUMBER DFHST8FS460
J 0
(-1270 4485);
DISPLAY 0.723404 (-1270 4485);
PAINT GREEN (-1270 4485);
DISPLAY INVISIBLE (-1270 4485);
FORCEPROP 2 LAST VALUE SCONN288_ADR50017-P087CC
J 0
(-1275 4600);
DISPLAY 1.021277 (-1275 4600);
FORCEPROP 2 LAST PART_TYPE SMLF
J 0
(-1275 4650);
DISPLAY 1.021277 (-1275 4650);
FORCEPROP 1 LAST MATERIAL IO
J 0
(-1270 4358);
DISPLAY 0.723404 (-1270 4358);
PAINT GREEN (-1270 4358);
FORCEPROP 1 LAST $LOCATION J2
J 0
(-1275 4550);
DISPLAY 0.723404 (-1275 4550);
PAINT GREEN (-1275 4550);
FORCEPROP 0 LASTPIN (-1425 1850) $PN 62
J 2
(-1435 1860);
DISPLAY 0.680851 (-1435 1860);
PAINT MONO (-1435 1860);
FORCEPROP 0 LASTPIN (-1425 3900) $PN 66
J 2
(-1435 3910);
DISPLAY 0.680851 (-1435 3910);
PAINT MONO (-1435 3910);
FORCEPROP 0 LASTPIN (-1425 3500) $PN 76
J 2
(-1435 3510);
DISPLAY 0.680851 (-1435 3510);
PAINT MONO (-1435 3510);
FORCEPROP 0 LASTPIN (-1425 3950) $PN 211
J 2
(-1435 3960);
DISPLAY 0.680851 (-1435 3960);
PAINT MONO (-1435 3960);
FORCEPROP 0 LASTPIN (-1425 3550) $PN 221
J 2
(-1435 3560);
DISPLAY 0.680851 (-1435 3560);
PAINT MONO (-1435 3560);
FORCEPROP 0 LASTPIN (-1425 4000) $PN 68
J 2
(-1435 4010);
DISPLAY 0.680851 (-1435 4010);
PAINT MONO (-1435 4010);
FORCEPROP 0 LASTPIN (-1425 3600) $PN 78
J 2
(-1435 3610);
DISPLAY 0.680851 (-1435 3610);
PAINT MONO (-1435 3610);
FORCEPROP 0 LASTPIN (-1425 4050) $PN 213
J 2
(-1435 4060);
DISPLAY 0.680851 (-1435 4060);
PAINT MONO (-1435 4060);
FORCEPROP 0 LASTPIN (-1425 3650) $PN 223
J 2
(-1435 3660);
DISPLAY 0.680851 (-1435 3660);
PAINT MONO (-1435 3660);
FORCEPROP 0 LASTPIN (-1425 4100) $PN 70
J 2
(-1435 4110);
DISPLAY 0.680851 (-1435 4110);
PAINT MONO (-1435 4110);
FORCEPROP 0 LASTPIN (-1425 3700) $PN 80
J 2
(-1435 3710);
DISPLAY 0.680851 (-1435 3710);
PAINT MONO (-1435 3710);
FORCEPROP 0 LASTPIN (-1425 4150) $PN 215
J 2
(-1435 4160);
DISPLAY 0.680851 (-1435 4160);
PAINT MONO (-1435 4160);
FORCEPROP 0 LASTPIN (-1425 3750) $PN 225
J 2
(-1435 3760);
DISPLAY 0.680851 (-1435 3760);
PAINT MONO (-1435 3760);
FORCEPROP 0 LASTPIN (-1425 4200) $PN 72
J 2
(-1435 4210);
DISPLAY 0.680851 (-1435 4210);
PAINT MONO (-1435 4210);
FORCEPROP 0 LASTPIN (-1425 3800) $PN 82
J 2
(-1435 3810);
DISPLAY 0.680851 (-1435 3810);
PAINT MONO (-1435 3810);
FORCEPROP 0 LASTPIN (-1425 2450) $PN 51
J 2
(-1435 2460);
DISPLAY 0.680851 (-1435 2460);
PAINT MONO (-1435 2460);
FORCEPROP 0 LASTPIN (-1425 2000) $PN 96
J 2
(-1435 2010);
DISPLAY 0.680851 (-1435 2010);
PAINT MONO (-1435 2010);
FORCEPROP 0 LASTPIN (-1425 2500) $PN 53
J 2
(-1435 2510);
DISPLAY 0.680851 (-1435 2510);
PAINT MONO (-1435 2510);
FORCEPROP 0 LASTPIN (-1425 2050) $PN 98
J 2
(-1435 2060);
DISPLAY 0.680851 (-1435 2060);
PAINT MONO (-1435 2060);
FORCEPROP 0 LASTPIN (-1425 2550) $PN 196
J 2
(-1435 2560);
DISPLAY 0.680851 (-1435 2560);
PAINT MONO (-1435 2560);
FORCEPROP 0 LASTPIN (-1425 2100) $PN 241
J 2
(-1435 2110);
DISPLAY 0.680851 (-1435 2110);
PAINT MONO (-1435 2110);
FORCEPROP 0 LASTPIN (-1425 2600) $PN 198
J 2
(-1435 2610);
DISPLAY 0.680851 (-1435 2610);
PAINT MONO (-1435 2610);
FORCEPROP 0 LASTPIN (-1425 2150) $PN 243
J 2
(-1435 2160);
DISPLAY 0.680851 (-1435 2160);
PAINT MONO (-1435 2160);
FORCEPROP 0 LASTPIN (-1425 2650) $PN 58
J 2
(-1435 2660);
DISPLAY 0.680851 (-1435 2660);
PAINT MONO (-1435 2660);
FORCEPROP 0 LASTPIN (-1425 2200) $PN 89
J 2
(-1435 2210);
DISPLAY 0.680851 (-1435 2210);
PAINT MONO (-1435 2210);
FORCEPROP 0 LASTPIN (-1425 2700) $PN 60
J 2
(-1435 2710);
DISPLAY 0.680851 (-1435 2710);
PAINT MONO (-1435 2710);
FORCEPROP 0 LASTPIN (-1425 2250) $PN 91
J 2
(-1435 2260);
DISPLAY 0.680851 (-1435 2260);
PAINT MONO (-1435 2260);
FORCEPROP 0 LASTPIN (-1425 2750) $PN 203
J 2
(-1435 2760);
DISPLAY 0.680851 (-1435 2760);
PAINT MONO (-1435 2760);
FORCEPROP 0 LASTPIN (-1425 2300) $PN 234
J 2
(-1435 2310);
DISPLAY 0.680851 (-1435 2310);
PAINT MONO (-1435 2310);
FORCEPROP 0 LASTPIN (-1425 2800) $PN 205
J 2
(-1435 2810);
DISPLAY 0.680851 (-1435 2810);
PAINT MONO (-1435 2810);
FORCEPROP 0 LASTPIN (-1425 2350) $PN 236
J 2
(-1435 2360);
DISPLAY 0.680851 (-1435 2360);
PAINT MONO (-1435 2360);
FORCEPROP 0 LASTPIN (-1425 2900) $PN 218
J 2
(-1435 2910);
DISPLAY 0.680851 (-1435 2910);
PAINT MONO (-1435 2910);
FORCEPROP 0 LASTPIN (-1425 2950) $PN 217
J 2
(-1435 2960);
DISPLAY 0.680851 (-1435 2960);
PAINT MONO (-1435 2960);
FORCEPROP 0 LASTPIN (-1425 3200) $PN 64
J 2
(-1435 3210);
DISPLAY 0.680851 (-1435 3210);
PAINT MONO (-1435 3210);
FORCEPROP 0 LASTPIN (-1425 3050) $PN 84
J 2
(-1435 3060);
DISPLAY 0.680851 (-1435 3060);
PAINT MONO (-1435 3060);
FORCEPROP 0 LASTPIN (-1425 3250) $PN 209
J 2
(-1435 3260);
DISPLAY 0.680851 (-1435 3260);
PAINT MONO (-1435 3260);
FORCEPROP 0 LASTPIN (-1425 3100) $PN 229
J 2
(-1435 3110);
DISPLAY 0.680851 (-1435 3110);
PAINT MONO (-1435 3110);
FORCEPROP 0 LASTPIN (-225 2650) $PN 7
J 0
(-215 2660);
DISPLAY 0.680851 (-215 2660);
PAINT MONO (-215 2660);
FORCEPROP 0 LASTPIN (-225 1000) $PN 100
J 0
(-215 1010);
DISPLAY 0.680851 (-215 1010);
PAINT MONO (-215 1010);
FORCEPROP 0 LASTPIN (-225 2700) $PN 9
J 0
(-215 2710);
DISPLAY 0.680851 (-215 2710);
PAINT MONO (-215 2710);
FORCEPROP 0 LASTPIN (-225 1050) $PN 102
J 0
(-215 1060);
DISPLAY 0.680851 (-215 1060);
PAINT MONO (-215 1060);
FORCEPROP 0 LASTPIN (-225 2750) $PN 152
J 0
(-215 2760);
DISPLAY 0.680851 (-215 2760);
PAINT MONO (-215 2760);
FORCEPROP 0 LASTPIN (-225 1100) $PN 245
J 0
(-215 1110);
DISPLAY 0.680851 (-215 1110);
PAINT MONO (-215 1110);
FORCEPROP 0 LASTPIN (-225 2800) $PN 154
J 0
(-215 2810);
DISPLAY 0.680851 (-215 2810);
PAINT MONO (-215 2810);
FORCEPROP 0 LASTPIN (-225 1150) $PN 247
J 0
(-215 1160);
DISPLAY 0.680851 (-215 1160);
PAINT MONO (-215 1160);
FORCEPROP 0 LASTPIN (-225 2850) $PN 14
J 0
(-215 2860);
DISPLAY 0.680851 (-215 2860);
PAINT MONO (-215 2860);
FORCEPROP 0 LASTPIN (-225 1200) $PN 107
J 0
(-215 1210);
DISPLAY 0.680851 (-215 1210);
PAINT MONO (-215 1210);
FORCEPROP 0 LASTPIN (-225 2900) $PN 16
J 0
(-215 2910);
DISPLAY 0.680851 (-215 2910);
PAINT MONO (-215 2910);
FORCEPROP 0 LASTPIN (-225 1250) $PN 109
J 0
(-215 1260);
DISPLAY 0.680851 (-215 1260);
PAINT MONO (-215 1260);
FORCEPROP 0 LASTPIN (-225 2950) $PN 159
J 0
(-215 2960);
DISPLAY 0.680851 (-215 2960);
PAINT MONO (-215 2960);
FORCEPROP 0 LASTPIN (-225 1300) $PN 252
J 0
(-215 1310);
DISPLAY 0.680851 (-215 1310);
PAINT MONO (-215 1310);
FORCEPROP 0 LASTPIN (-225 3000) $PN 161
J 0
(-215 3010);
DISPLAY 0.680851 (-215 3010);
PAINT MONO (-215 3010);
FORCEPROP 0 LASTPIN (-225 1350) $PN 254
J 0
(-215 1360);
DISPLAY 0.680851 (-215 1360);
PAINT MONO (-215 1360);
FORCEPROP 0 LASTPIN (-225 3050) $PN 18
J 0
(-215 3060);
DISPLAY 0.680851 (-215 3060);
PAINT MONO (-215 3060);
FORCEPROP 0 LASTPIN (-225 1400) $PN 111
J 0
(-215 1410);
DISPLAY 0.680851 (-215 1410);
PAINT MONO (-215 1410);
FORCEPROP 0 LASTPIN (-225 3100) $PN 20
J 0
(-215 3110);
DISPLAY 0.680851 (-215 3110);
PAINT MONO (-215 3110);
FORCEPROP 0 LASTPIN (-225 1450) $PN 113
J 0
(-215 1460);
DISPLAY 0.680851 (-215 1460);
PAINT MONO (-215 1460);
FORCEPROP 0 LASTPIN (-225 3150) $PN 163
J 0
(-215 3160);
DISPLAY 0.680851 (-215 3160);
PAINT MONO (-215 3160);
FORCEPROP 0 LASTPIN (-225 1500) $PN 256
J 0
(-215 1510);
DISPLAY 0.680851 (-215 1510);
PAINT MONO (-215 1510);
FORCEPROP 0 LASTPIN (-225 3200) $PN 165
J 0
(-215 3210);
DISPLAY 0.680851 (-215 3210);
PAINT MONO (-215 3210);
FORCEPROP 0 LASTPIN (-225 1550) $PN 258
J 0
(-215 1560);
DISPLAY 0.680851 (-215 1560);
PAINT MONO (-215 1560);
FORCEPROP 0 LASTPIN (-225 3250) $PN 25
J 0
(-215 3260);
DISPLAY 0.680851 (-215 3260);
PAINT MONO (-215 3260);
FORCEPROP 0 LASTPIN (-225 1600) $PN 118
J 0
(-215 1610);
DISPLAY 0.680851 (-215 1610);
PAINT MONO (-215 1610);
FORCEPROP 0 LASTPIN (-225 3300) $PN 27
J 0
(-215 3310);
DISPLAY 0.680851 (-215 3310);
PAINT MONO (-215 3310);
FORCEPROP 0 LASTPIN (-225 1650) $PN 120
J 0
(-215 1660);
DISPLAY 0.680851 (-215 1660);
PAINT MONO (-215 1660);
FORCEPROP 0 LASTPIN (-225 3350) $PN 170
J 0
(-215 3360);
DISPLAY 0.680851 (-215 3360);
PAINT MONO (-215 3360);
FORCEPROP 0 LASTPIN (-225 1700) $PN 263
J 0
(-215 1710);
DISPLAY 0.680851 (-215 1710);
PAINT MONO (-215 1710);
FORCEPROP 0 LASTPIN (-225 3400) $PN 172
J 0
(-215 3410);
DISPLAY 0.680851 (-215 3410);
PAINT MONO (-215 3410);
FORCEPROP 0 LASTPIN (-225 1750) $PN 265
J 0
(-215 1760);
DISPLAY 0.680851 (-215 1760);
PAINT MONO (-215 1760);
FORCEPROP 0 LASTPIN (-225 3450) $PN 29
J 0
(-215 3460);
DISPLAY 0.680851 (-215 3460);
PAINT MONO (-215 3460);
FORCEPROP 0 LASTPIN (-225 1800) $PN 122
J 0
(-215 1810);
DISPLAY 0.680851 (-215 1810);
PAINT MONO (-215 1810);
FORCEPROP 0 LASTPIN (-225 3500) $PN 31
J 0
(-215 3510);
DISPLAY 0.680851 (-215 3510);
PAINT MONO (-215 3510);
FORCEPROP 0 LASTPIN (-225 1850) $PN 124
J 0
(-215 1860);
DISPLAY 0.680851 (-215 1860);
PAINT MONO (-215 1860);
FORCEPROP 0 LASTPIN (-225 3550) $PN 174
J 0
(-215 3560);
DISPLAY 0.680851 (-215 3560);
PAINT MONO (-215 3560);
FORCEPROP 0 LASTPIN (-225 1900) $PN 267
J 0
(-215 1910);
DISPLAY 0.680851 (-215 1910);
PAINT MONO (-215 1910);
FORCEPROP 0 LASTPIN (-225 3600) $PN 176
J 0
(-215 3610);
DISPLAY 0.680851 (-215 3610);
PAINT MONO (-215 3610);
FORCEPROP 0 LASTPIN (-225 1950) $PN 269
J 0
(-215 1960);
DISPLAY 0.680851 (-215 1960);
PAINT MONO (-215 1960);
FORCEPROP 0 LASTPIN (-225 3650) $PN 36
J 0
(-215 3660);
DISPLAY 0.680851 (-215 3660);
PAINT MONO (-215 3660);
FORCEPROP 0 LASTPIN (-225 2000) $PN 129
J 0
(-215 2010);
DISPLAY 0.680851 (-215 2010);
PAINT MONO (-215 2010);
FORCEPROP 0 LASTPIN (-225 3700) $PN 38
J 0
(-215 3710);
DISPLAY 0.680851 (-215 3710);
PAINT MONO (-215 3710);
FORCEPROP 0 LASTPIN (-225 2050) $PN 131
J 0
(-215 2060);
DISPLAY 0.680851 (-215 2060);
PAINT MONO (-215 2060);
FORCEPROP 0 LASTPIN (-225 3750) $PN 181
J 0
(-215 3760);
DISPLAY 0.680851 (-215 3760);
PAINT MONO (-215 3760);
FORCEPROP 0 LASTPIN (-225 2100) $PN 274
J 0
(-215 2110);
DISPLAY 0.680851 (-215 2110);
PAINT MONO (-215 2110);
FORCEPROP 0 LASTPIN (-225 3800) $PN 183
J 0
(-215 3810);
DISPLAY 0.680851 (-215 3810);
PAINT MONO (-215 3810);
FORCEPROP 0 LASTPIN (-225 2150) $PN 276
J 0
(-215 2160);
DISPLAY 0.680851 (-215 2160);
PAINT MONO (-215 2160);
FORCEPROP 0 LASTPIN (-225 3850) $PN 40
J 0
(-215 3860);
DISPLAY 0.680851 (-215 3860);
PAINT MONO (-215 3860);
FORCEPROP 0 LASTPIN (-225 2200) $PN 133
J 0
(-215 2210);
DISPLAY 0.680851 (-215 2210);
PAINT MONO (-215 2210);
FORCEPROP 0 LASTPIN (-225 3900) $PN 42
J 0
(-215 3910);
DISPLAY 0.680851 (-215 3910);
PAINT MONO (-215 3910);
FORCEPROP 0 LASTPIN (-225 2250) $PN 135
J 0
(-215 2260);
DISPLAY 0.680851 (-215 2260);
PAINT MONO (-215 2260);
FORCEPROP 0 LASTPIN (-225 3950) $PN 185
J 0
(-215 3960);
DISPLAY 0.680851 (-215 3960);
PAINT MONO (-215 3960);
FORCEPROP 0 LASTPIN (-225 2300) $PN 278
J 0
(-215 2310);
DISPLAY 0.680851 (-215 2310);
PAINT MONO (-215 2310);
FORCEPROP 0 LASTPIN (-225 4000) $PN 187
J 0
(-215 4010);
DISPLAY 0.680851 (-215 4010);
PAINT MONO (-215 4010);
FORCEPROP 0 LASTPIN (-225 2350) $PN 280
J 0
(-215 2360);
DISPLAY 0.680851 (-215 2360);
PAINT MONO (-215 2360);
FORCEPROP 0 LASTPIN (-225 4050) $PN 47
J 0
(-215 4060);
DISPLAY 0.680851 (-215 4060);
PAINT MONO (-215 4060);
FORCEPROP 0 LASTPIN (-225 2400) $PN 140
J 0
(-215 2410);
DISPLAY 0.680851 (-215 2410);
PAINT MONO (-215 2410);
FORCEPROP 0 LASTPIN (-225 4100) $PN 49
J 0
(-215 4110);
DISPLAY 0.680851 (-215 4110);
PAINT MONO (-215 4110);
FORCEPROP 0 LASTPIN (-225 2450) $PN 142
J 0
(-215 2460);
DISPLAY 0.680851 (-215 2460);
PAINT MONO (-215 2460);
FORCEPROP 0 LASTPIN (-225 4150) $PN 192
J 0
(-215 4160);
DISPLAY 0.680851 (-215 4160);
PAINT MONO (-215 4160);
FORCEPROP 0 LASTPIN (-225 2500) $PN 285
J 0
(-215 2510);
DISPLAY 0.680851 (-215 2510);
PAINT MONO (-215 2510);
FORCEPROP 0 LASTPIN (-225 4200) $PN 194
J 0
(-215 4210);
DISPLAY 0.680851 (-215 4210);
PAINT MONO (-215 4210);
FORCEPROP 0 LASTPIN (-225 2550) $PN 287
J 0
(-215 2560);
DISPLAY 0.680851 (-215 2560);
PAINT MONO (-215 2560);
FORCEPROP 0 LASTPIN (-1425 1700) $PN 148
J 2
(-1435 1710);
DISPLAY 0.680851 (-1435 1710);
PAINT MONO (-1435 1710);
FORCEPROP 0 LASTPIN (-1425 1600) $PN 4
J 2
(-1435 1610);
DISPLAY 0.680851 (-1435 1610);
PAINT MONO (-1435 1610);
FORCEPROP 0 LASTPIN (-1425 1650) $PN 5
J 2
(-1435 1660);
DISPLAY 0.680851 (-1435 1660);
PAINT MONO (-1435 1660);
FORCEPROP 0 LASTPIN (-1425 800) $PN 86
J 2
(-1435 810);
DISPLAY 0.680851 (-1435 810);
PAINT MONO (-1435 810);
FORCEPROP 0 LASTPIN (-1425 750) $PN 87
J 2
(-1435 760);
DISPLAY 0.680851 (-1435 760);
PAINT MONO (-1435 760);
FORCEPROP 0 LASTPIN (-1425 3400) $PN 74
J 2
(-1435 3410);
DISPLAY 0.680851 (-1435 3410);
PAINT MONO (-1435 3410);
FORCEPROP 0 LASTPIN (-1425 3350) $PN 227
J 2
(-1435 3360);
DISPLAY 0.680851 (-1435 3360);
PAINT MONO (-1435 3360);
FORCEPROP 0 LASTPIN (-1425 1350) $PN 147
J 2
(-1435 1360);
DISPLAY 0.680851 (-1435 1360);
PAINT MONO (-1435 1360);
FORCEPROP 0 LASTPIN (-1425 1900) $PN 207
J 2
(-1435 1910);
DISPLAY 0.680851 (-1435 1910);
PAINT MONO (-1435 1910);
FORCEPROP 0 LASTPIN (-1425 950) $PN 2
J 2
(-1435 960);
DISPLAY 0.680851 (-1435 960);
PAINT MONO (-1435 960);
FORCEPROP 0 LASTPIN (-1425 1000) $PN 144
J 2
(-1435 1010);
DISPLAY 0.680851 (-1435 1010);
PAINT MONO (-1435 1010);
FORCEPROP 0 LASTPIN (-1425 1050) $PN 149
J 2
(-1435 1060);
DISPLAY 0.680851 (-1435 1060);
PAINT MONO (-1435 1060);
FORCEPROP 0 LASTPIN (-1425 1100) $PN 150
J 2
(-1435 1110);
DISPLAY 0.680851 (-1435 1110);
PAINT MONO (-1435 1110);
FORCEPROP 0 LASTPIN (-1425 1150) $PN 220
J 2
(-1435 1160);
DISPLAY 0.680851 (-1435 1160);
PAINT MONO (-1435 1160);
FORCEPROP 0 LASTPIN (-1425 1200) $PN 231
J 2
(-1435 1210);
DISPLAY 0.680851 (-1435 1210);
PAINT MONO (-1435 1210);
FORCEPROP 0 LASTPIN (-1425 1250) $PN 232
J 2
(-1435 1260);
DISPLAY 0.680851 (-1435 1260);
PAINT MONO (-1435 1260);
FORCEPROP 0 LASTPIN (-1425 1750) $PN 3
J 2
(-1435 1760);
DISPLAY 0.680851 (-1435 1760);
PAINT MONO (-1435 1760);
FORCEPROP 2 LAST CDS_LIB pure_quanta
J 0
(-825 2475);
DISPLAY INVISIBLE (-825 2475);
FORCEPROP 1 LAST CDS_LMAN_SYM_OUTLINE -450,1875,450,-1875
J 0
(-825 2475);
DISPLAY 0.468085 (-825 2475);
PAINT GREEN (-825 2475);
DISPLAY INVISIBLE (-825 2475);
FORCEPROP 1 LAST NEEDS_NO_SIZE TRUE
J 0
(-825 2475);
DISPLAY 0.723404 (-825 2475);
PAINT GREEN (-825 2475);
DISPLAY INVISIBLE (-825 2475);
FORCEPROP 2 LAST CDS_LOCATION J2
J 0
(-1275 4700);
DISPLAY 1.021277 (-1275 4700);
DISPLAY INVISIBLE (-1275 4700);
FORCEPROP 0 LAST $SEC 1
J 0
(-1275 4700);
DISPLAY 0.680851 (-1275 4700);
PAINT MONO (-1275 4700);
DISPLAY INVISIBLE (-1275 4700);
FORCEPROP 2 LAST CDS_SEC 1
J 0
(-1275 4700);
DISPLAY 1.021277 (-1275 4700);
DISPLAY INVISIBLE (-1275 4700);
FORCEPROP 1 LAST PATH I177
J 0
(-825 2475);
DISPLAY 0.723404 (-825 2475);
PAINT GREEN (-825 2475);
DISPLAY INVISIBLE (-825 2475);
FORCEADD SCONN288_ADR50017P087CC..3
(5200 2575);
FORCEPROP 1 LAST PART_NUMBER DFHST8FS460
J 0
(4745 4499);
DISPLAY 0.723404 (4745 4499);
PAINT GREEN (4745 4499);
DISPLAY INVISIBLE (4745 4499);
FORCEPROP 1 LAST MATERIAL IO
J 0
(4745 4372);
DISPLAY 0.723404 (4745 4372);
PAINT GREEN (4745 4372);
FORCEPROP 2 LAST PART_TYPE SMLF
J 0
(4750 4650);
DISPLAY 1.021277 (4750 4650);
FORCEPROP 2 LAST VALUE SCONN288_ADR50017-P087CC
J 0
(4750 4600);
DISPLAY 1.021277 (4750 4600);
FORCEPROP 1 LAST $LOCATION J2
J 0
(4750 4550);
DISPLAY 0.723404 (4750 4550);
PAINT GREEN (4750 4550);
FORCEPROP 0 LASTPIN (5800 950) $PN G1
J 0
(5810 960);
DISPLAY 0.680851 (5810 960);
PAINT MONO (5810 960);
FORCEPROP 0 LASTPIN (5800 900) $PN G2
J 0
(5810 910);
DISPLAY 0.680851 (5810 910);
PAINT MONO (5810 910);
FORCEPROP 0 LASTPIN (5800 850) $PN G3
J 0
(5810 860);
DISPLAY 0.680851 (5810 860);
PAINT MONO (5810 860);
FORCEPROP 0 LASTPIN (4600 4100) $PN 1
J 2
(4590 4110);
DISPLAY 0.680851 (4590 4110);
PAINT MONO (4590 4110);
FORCEPROP 0 LASTPIN (4600 4150) $PN 145
J 2
(4590 4160);
DISPLAY 0.680851 (4590 4160);
PAINT MONO (4590 4160);
FORCEPROP 0 LASTPIN (4600 4200) $PN 146
J 2
(4590 4210);
DISPLAY 0.680851 (4590 4210);
PAINT MONO (4590 4210);
FORCEPROP 0 LASTPIN (5800 1050) $PN 6
J 0
(5810 1060);
DISPLAY 0.680851 (5810 1060);
PAINT MONO (5810 1060);
FORCEPROP 0 LASTPIN (5800 1100) $PN 8
J 0
(5810 1110);
DISPLAY 0.680851 (5810 1110);
PAINT MONO (5810 1110);
FORCEPROP 0 LASTPIN (5800 1150) $PN 10
J 0
(5810 1160);
DISPLAY 0.680851 (5810 1160);
PAINT MONO (5810 1160);
FORCEPROP 0 LASTPIN (5800 1200) $PN 13
J 0
(5810 1210);
DISPLAY 0.680851 (5810 1210);
PAINT MONO (5810 1210);
FORCEPROP 0 LASTPIN (5800 1250) $PN 15
J 0
(5810 1260);
DISPLAY 0.680851 (5810 1260);
PAINT MONO (5810 1260);
FORCEPROP 0 LASTPIN (5800 1300) $PN 17
J 0
(5810 1310);
DISPLAY 0.680851 (5810 1310);
PAINT MONO (5810 1310);
FORCEPROP 0 LASTPIN (5800 1350) $PN 19
J 0
(5810 1360);
DISPLAY 0.680851 (5810 1360);
PAINT MONO (5810 1360);
FORCEPROP 0 LASTPIN (5800 1400) $PN 21
J 0
(5810 1410);
DISPLAY 0.680851 (5810 1410);
PAINT MONO (5810 1410);
FORCEPROP 0 LASTPIN (5800 1450) $PN 24
J 0
(5810 1460);
DISPLAY 0.680851 (5810 1460);
PAINT MONO (5810 1460);
FORCEPROP 0 LASTPIN (5800 1500) $PN 26
J 0
(5810 1510);
DISPLAY 0.680851 (5810 1510);
PAINT MONO (5810 1510);
FORCEPROP 0 LASTPIN (5800 1550) $PN 28
J 0
(5810 1560);
DISPLAY 0.680851 (5810 1560);
PAINT MONO (5810 1560);
FORCEPROP 0 LASTPIN (5800 1600) $PN 30
J 0
(5810 1610);
DISPLAY 0.680851 (5810 1610);
PAINT MONO (5810 1610);
FORCEPROP 0 LASTPIN (5800 1650) $PN 32
J 0
(5810 1660);
DISPLAY 0.680851 (5810 1660);
PAINT MONO (5810 1660);
FORCEPROP 0 LASTPIN (5800 1700) $PN 35
J 0
(5810 1710);
DISPLAY 0.680851 (5810 1710);
PAINT MONO (5810 1710);
FORCEPROP 0 LASTPIN (5800 1750) $PN 37
J 0
(5810 1760);
DISPLAY 0.680851 (5810 1760);
PAINT MONO (5810 1760);
FORCEPROP 0 LASTPIN (5800 1800) $PN 39
J 0
(5810 1810);
DISPLAY 0.680851 (5810 1810);
PAINT MONO (5810 1810);
FORCEPROP 0 LASTPIN (5800 1850) $PN 41
J 0
(5810 1860);
DISPLAY 0.680851 (5810 1860);
PAINT MONO (5810 1860);
FORCEPROP 0 LASTPIN (5800 1900) $PN 43
J 0
(5810 1910);
DISPLAY 0.680851 (5810 1910);
PAINT MONO (5810 1910);
FORCEPROP 0 LASTPIN (5800 1950) $PN 46
J 0
(5810 1960);
DISPLAY 0.680851 (5810 1960);
PAINT MONO (5810 1960);
FORCEPROP 0 LASTPIN (5800 2000) $PN 48
J 0
(5810 2010);
DISPLAY 0.680851 (5810 2010);
PAINT MONO (5810 2010);
FORCEPROP 0 LASTPIN (5800 2050) $PN 50
J 0
(5810 2060);
DISPLAY 0.680851 (5810 2060);
PAINT MONO (5810 2060);
FORCEPROP 0 LASTPIN (5800 2100) $PN 52
J 0
(5810 2110);
DISPLAY 0.680851 (5810 2110);
PAINT MONO (5810 2110);
FORCEPROP 0 LASTPIN (5800 2150) $PN 54
J 0
(5810 2160);
DISPLAY 0.680851 (5810 2160);
PAINT MONO (5810 2160);
FORCEPROP 0 LASTPIN (5800 2200) $PN 57
J 0
(5810 2210);
DISPLAY 0.680851 (5810 2210);
PAINT MONO (5810 2210);
FORCEPROP 0 LASTPIN (5800 2250) $PN 59
J 0
(5810 2260);
DISPLAY 0.680851 (5810 2260);
PAINT MONO (5810 2260);
FORCEPROP 0 LASTPIN (5800 2300) $PN 61
J 0
(5810 2310);
DISPLAY 0.680851 (5810 2310);
PAINT MONO (5810 2310);
FORCEPROP 0 LASTPIN (5800 2350) $PN 63
J 0
(5810 2360);
DISPLAY 0.680851 (5810 2360);
PAINT MONO (5810 2360);
FORCEPROP 0 LASTPIN (5800 2400) $PN 65
J 0
(5810 2410);
DISPLAY 0.680851 (5810 2410);
PAINT MONO (5810 2410);
FORCEPROP 0 LASTPIN (5800 2450) $PN 67
J 0
(5810 2460);
DISPLAY 0.680851 (5810 2460);
PAINT MONO (5810 2460);
FORCEPROP 0 LASTPIN (5800 2500) $PN 69
J 0
(5810 2510);
DISPLAY 0.680851 (5810 2510);
PAINT MONO (5810 2510);
FORCEPROP 0 LASTPIN (5800 2550) $PN 71
J 0
(5810 2560);
DISPLAY 0.680851 (5810 2560);
PAINT MONO (5810 2560);
FORCEPROP 0 LASTPIN (5800 2600) $PN 73
J 0
(5810 2610);
DISPLAY 0.680851 (5810 2610);
PAINT MONO (5810 2610);
FORCEPROP 0 LASTPIN (5800 2650) $PN 75
J 0
(5810 2660);
DISPLAY 0.680851 (5810 2660);
PAINT MONO (5810 2660);
FORCEPROP 0 LASTPIN (5800 2700) $PN 77
J 0
(5810 2710);
DISPLAY 0.680851 (5810 2710);
PAINT MONO (5810 2710);
FORCEPROP 0 LASTPIN (5800 2750) $PN 79
J 0
(5810 2760);
DISPLAY 0.680851 (5810 2760);
PAINT MONO (5810 2760);
FORCEPROP 0 LASTPIN (5800 2800) $PN 81
J 0
(5810 2810);
DISPLAY 0.680851 (5810 2810);
PAINT MONO (5810 2810);
FORCEPROP 0 LASTPIN (5800 2850) $PN 83
J 0
(5810 2860);
DISPLAY 0.680851 (5810 2860);
PAINT MONO (5810 2860);
FORCEPROP 0 LASTPIN (5800 2900) $PN 85
J 0
(5810 2910);
DISPLAY 0.680851 (5810 2910);
PAINT MONO (5810 2910);
FORCEPROP 0 LASTPIN (5800 2950) $PN 88
J 0
(5810 2960);
DISPLAY 0.680851 (5810 2960);
PAINT MONO (5810 2960);
FORCEPROP 0 LASTPIN (5800 3000) $PN 90
J 0
(5810 3010);
DISPLAY 0.680851 (5810 3010);
PAINT MONO (5810 3010);
FORCEPROP 0 LASTPIN (5800 3050) $PN 92
J 0
(5810 3060);
DISPLAY 0.680851 (5810 3060);
PAINT MONO (5810 3060);
FORCEPROP 0 LASTPIN (5800 3100) $PN 95
J 0
(5810 3110);
DISPLAY 0.680851 (5810 3110);
PAINT MONO (5810 3110);
FORCEPROP 0 LASTPIN (5800 3150) $PN 97
J 0
(5810 3160);
DISPLAY 0.680851 (5810 3160);
PAINT MONO (5810 3160);
FORCEPROP 0 LASTPIN (5800 3200) $PN 99
J 0
(5810 3210);
DISPLAY 0.680851 (5810 3210);
PAINT MONO (5810 3210);
FORCEPROP 0 LASTPIN (5800 3250) $PN 101
J 0
(5810 3260);
DISPLAY 0.680851 (5810 3260);
PAINT MONO (5810 3260);
FORCEPROP 0 LASTPIN (5800 3300) $PN 103
J 0
(5810 3310);
DISPLAY 0.680851 (5810 3310);
PAINT MONO (5810 3310);
FORCEPROP 0 LASTPIN (5800 3350) $PN 106
J 0
(5810 3360);
DISPLAY 0.680851 (5810 3360);
PAINT MONO (5810 3360);
FORCEPROP 0 LASTPIN (5800 3400) $PN 108
J 0
(5810 3410);
DISPLAY 0.680851 (5810 3410);
PAINT MONO (5810 3410);
FORCEPROP 0 LASTPIN (5800 3450) $PN 110
J 0
(5810 3460);
DISPLAY 0.680851 (5810 3460);
PAINT MONO (5810 3460);
FORCEPROP 0 LASTPIN (5800 3500) $PN 112
J 0
(5810 3510);
DISPLAY 0.680851 (5810 3510);
PAINT MONO (5810 3510);
FORCEPROP 0 LASTPIN (5800 3550) $PN 114
J 0
(5810 3560);
DISPLAY 0.680851 (5810 3560);
PAINT MONO (5810 3560);
FORCEPROP 0 LASTPIN (5800 3600) $PN 117
J 0
(5810 3610);
DISPLAY 0.680851 (5810 3610);
PAINT MONO (5810 3610);
FORCEPROP 0 LASTPIN (5800 3650) $PN 119
J 0
(5810 3660);
DISPLAY 0.680851 (5810 3660);
PAINT MONO (5810 3660);
FORCEPROP 0 LASTPIN (5800 3700) $PN 121
J 0
(5810 3710);
DISPLAY 0.680851 (5810 3710);
PAINT MONO (5810 3710);
FORCEPROP 0 LASTPIN (5800 3750) $PN 123
J 0
(5810 3760);
DISPLAY 0.680851 (5810 3760);
PAINT MONO (5810 3760);
FORCEPROP 0 LASTPIN (5800 3800) $PN 125
J 0
(5810 3810);
DISPLAY 0.680851 (5810 3810);
PAINT MONO (5810 3810);
FORCEPROP 0 LASTPIN (5800 3850) $PN 128
J 0
(5810 3860);
DISPLAY 0.680851 (5810 3860);
PAINT MONO (5810 3860);
FORCEPROP 0 LASTPIN (5800 3900) $PN 130
J 0
(5810 3910);
DISPLAY 0.680851 (5810 3910);
PAINT MONO (5810 3910);
FORCEPROP 0 LASTPIN (5800 3950) $PN 132
J 0
(5810 3960);
DISPLAY 0.680851 (5810 3960);
PAINT MONO (5810 3960);
FORCEPROP 0 LASTPIN (5800 4000) $PN 134
J 0
(5810 4010);
DISPLAY 0.680851 (5810 4010);
PAINT MONO (5810 4010);
FORCEPROP 0 LASTPIN (5800 4050) $PN 136
J 0
(5810 4060);
DISPLAY 0.680851 (5810 4060);
PAINT MONO (5810 4060);
FORCEPROP 0 LASTPIN (5800 4100) $PN 139
J 0
(5810 4110);
DISPLAY 0.680851 (5810 4110);
PAINT MONO (5810 4110);
FORCEPROP 0 LASTPIN (5800 4150) $PN 141
J 0
(5810 4160);
DISPLAY 0.680851 (5810 4160);
PAINT MONO (5810 4160);
FORCEPROP 0 LASTPIN (5800 4200) $PN 143
J 0
(5810 4210);
DISPLAY 0.680851 (5810 4210);
PAINT MONO (5810 4210);
FORCEPROP 0 LASTPIN (4600 950) $PN 151
J 2
(4590 960);
DISPLAY 0.680851 (4590 960);
PAINT MONO (4590 960);
FORCEPROP 0 LASTPIN (4600 1000) $PN 153
J 2
(4590 1010);
DISPLAY 0.680851 (4590 1010);
PAINT MONO (4590 1010);
FORCEPROP 0 LASTPIN (4600 1050) $PN 155
J 2
(4590 1060);
DISPLAY 0.680851 (4590 1060);
PAINT MONO (4590 1060);
FORCEPROP 0 LASTPIN (4600 1100) $PN 158
J 2
(4590 1110);
DISPLAY 0.680851 (4590 1110);
PAINT MONO (4590 1110);
FORCEPROP 0 LASTPIN (4600 1150) $PN 160
J 2
(4590 1160);
DISPLAY 0.680851 (4590 1160);
PAINT MONO (4590 1160);
FORCEPROP 0 LASTPIN (4600 1200) $PN 162
J 2
(4590 1210);
DISPLAY 0.680851 (4590 1210);
PAINT MONO (4590 1210);
FORCEPROP 0 LASTPIN (4600 1250) $PN 164
J 2
(4590 1260);
DISPLAY 0.680851 (4590 1260);
PAINT MONO (4590 1260);
FORCEPROP 0 LASTPIN (4600 1300) $PN 166
J 2
(4590 1310);
DISPLAY 0.680851 (4590 1310);
PAINT MONO (4590 1310);
FORCEPROP 0 LASTPIN (4600 1350) $PN 169
J 2
(4590 1360);
DISPLAY 0.680851 (4590 1360);
PAINT MONO (4590 1360);
FORCEPROP 0 LASTPIN (4600 1400) $PN 171
J 2
(4590 1410);
DISPLAY 0.680851 (4590 1410);
PAINT MONO (4590 1410);
FORCEPROP 0 LASTPIN (4600 1450) $PN 173
J 2
(4590 1460);
DISPLAY 0.680851 (4590 1460);
PAINT MONO (4590 1460);
FORCEPROP 0 LASTPIN (4600 1500) $PN 175
J 2
(4590 1510);
DISPLAY 0.680851 (4590 1510);
PAINT MONO (4590 1510);
FORCEPROP 0 LASTPIN (4600 1550) $PN 177
J 2
(4590 1560);
DISPLAY 0.680851 (4590 1560);
PAINT MONO (4590 1560);
FORCEPROP 0 LASTPIN (4600 1600) $PN 180
J 2
(4590 1610);
DISPLAY 0.680851 (4590 1610);
PAINT MONO (4590 1610);
FORCEPROP 0 LASTPIN (4600 1650) $PN 182
J 2
(4590 1660);
DISPLAY 0.680851 (4590 1660);
PAINT MONO (4590 1660);
FORCEPROP 0 LASTPIN (4600 1700) $PN 184
J 2
(4590 1710);
DISPLAY 0.680851 (4590 1710);
PAINT MONO (4590 1710);
FORCEPROP 0 LASTPIN (4600 1750) $PN 186
J 2
(4590 1760);
DISPLAY 0.680851 (4590 1760);
PAINT MONO (4590 1760);
FORCEPROP 0 LASTPIN (4600 1800) $PN 188
J 2
(4590 1810);
DISPLAY 0.680851 (4590 1810);
PAINT MONO (4590 1810);
FORCEPROP 0 LASTPIN (4600 1850) $PN 191
J 2
(4590 1860);
DISPLAY 0.680851 (4590 1860);
PAINT MONO (4590 1860);
FORCEPROP 0 LASTPIN (4600 1900) $PN 193
J 2
(4590 1910);
DISPLAY 0.680851 (4590 1910);
PAINT MONO (4590 1910);
FORCEPROP 0 LASTPIN (4600 1950) $PN 195
J 2
(4590 1960);
DISPLAY 0.680851 (4590 1960);
PAINT MONO (4590 1960);
FORCEPROP 0 LASTPIN (4600 2000) $PN 197
J 2
(4590 2010);
DISPLAY 0.680851 (4590 2010);
PAINT MONO (4590 2010);
FORCEPROP 0 LASTPIN (4600 2050) $PN 199
J 2
(4590 2060);
DISPLAY 0.680851 (4590 2060);
PAINT MONO (4590 2060);
FORCEPROP 0 LASTPIN (4600 2100) $PN 202
J 2
(4590 2110);
DISPLAY 0.680851 (4590 2110);
PAINT MONO (4590 2110);
FORCEPROP 0 LASTPIN (4600 2150) $PN 204
J 2
(4590 2160);
DISPLAY 0.680851 (4590 2160);
PAINT MONO (4590 2160);
FORCEPROP 0 LASTPIN (4600 2200) $PN 206
J 2
(4590 2210);
DISPLAY 0.680851 (4590 2210);
PAINT MONO (4590 2210);
FORCEPROP 0 LASTPIN (4600 2250) $PN 208
J 2
(4590 2260);
DISPLAY 0.680851 (4590 2260);
PAINT MONO (4590 2260);
FORCEPROP 0 LASTPIN (4600 2300) $PN 210
J 2
(4590 2310);
DISPLAY 0.680851 (4590 2310);
PAINT MONO (4590 2310);
FORCEPROP 0 LASTPIN (4600 2350) $PN 212
J 2
(4590 2360);
DISPLAY 0.680851 (4590 2360);
PAINT MONO (4590 2360);
FORCEPROP 0 LASTPIN (4600 2400) $PN 214
J 2
(4590 2410);
DISPLAY 0.680851 (4590 2410);
PAINT MONO (4590 2410);
FORCEPROP 0 LASTPIN (4600 2450) $PN 216
J 2
(4590 2460);
DISPLAY 0.680851 (4590 2460);
PAINT MONO (4590 2460);
FORCEPROP 0 LASTPIN (4600 2500) $PN 219
J 2
(4590 2510);
DISPLAY 0.680851 (4590 2510);
PAINT MONO (4590 2510);
FORCEPROP 0 LASTPIN (4600 2550) $PN 222
J 2
(4590 2560);
DISPLAY 0.680851 (4590 2560);
PAINT MONO (4590 2560);
FORCEPROP 0 LASTPIN (4600 2600) $PN 224
J 2
(4590 2610);
DISPLAY 0.680851 (4590 2610);
PAINT MONO (4590 2610);
FORCEPROP 0 LASTPIN (4600 2650) $PN 226
J 2
(4590 2660);
DISPLAY 0.680851 (4590 2660);
PAINT MONO (4590 2660);
FORCEPROP 0 LASTPIN (4600 2700) $PN 228
J 2
(4590 2710);
DISPLAY 0.680851 (4590 2710);
PAINT MONO (4590 2710);
FORCEPROP 0 LASTPIN (4600 2750) $PN 230
J 2
(4590 2760);
DISPLAY 0.680851 (4590 2760);
PAINT MONO (4590 2760);
FORCEPROP 0 LASTPIN (4600 2800) $PN 233
J 2
(4590 2810);
DISPLAY 0.680851 (4590 2810);
PAINT MONO (4590 2810);
FORCEPROP 0 LASTPIN (4600 2850) $PN 235
J 2
(4590 2860);
DISPLAY 0.680851 (4590 2860);
PAINT MONO (4590 2860);
FORCEPROP 0 LASTPIN (4600 2900) $PN 237
J 2
(4590 2910);
DISPLAY 0.680851 (4590 2910);
PAINT MONO (4590 2910);
FORCEPROP 0 LASTPIN (4600 2950) $PN 240
J 2
(4590 2960);
DISPLAY 0.680851 (4590 2960);
PAINT MONO (4590 2960);
FORCEPROP 0 LASTPIN (4600 3000) $PN 242
J 2
(4590 3010);
DISPLAY 0.680851 (4590 3010);
PAINT MONO (4590 3010);
FORCEPROP 0 LASTPIN (4600 3050) $PN 244
J 2
(4590 3060);
DISPLAY 0.680851 (4590 3060);
PAINT MONO (4590 3060);
FORCEPROP 0 LASTPIN (4600 3100) $PN 246
J 2
(4590 3110);
DISPLAY 0.680851 (4590 3110);
PAINT MONO (4590 3110);
FORCEPROP 0 LASTPIN (4600 3150) $PN 248
J 2
(4590 3160);
DISPLAY 0.680851 (4590 3160);
PAINT MONO (4590 3160);
FORCEPROP 0 LASTPIN (4600 3200) $PN 251
J 2
(4590 3210);
DISPLAY 0.680851 (4590 3210);
PAINT MONO (4590 3210);
FORCEPROP 0 LASTPIN (4600 3250) $PN 253
J 2
(4590 3260);
DISPLAY 0.680851 (4590 3260);
PAINT MONO (4590 3260);
FORCEPROP 0 LASTPIN (4600 3300) $PN 255
J 2
(4590 3310);
DISPLAY 0.680851 (4590 3310);
PAINT MONO (4590 3310);
FORCEPROP 0 LASTPIN (4600 3350) $PN 257
J 2
(4590 3360);
DISPLAY 0.680851 (4590 3360);
PAINT MONO (4590 3360);
FORCEPROP 0 LASTPIN (4600 3400) $PN 259
J 2
(4590 3410);
DISPLAY 0.680851 (4590 3410);
PAINT MONO (4590 3410);
FORCEPROP 0 LASTPIN (4600 3450) $PN 262
J 2
(4590 3460);
DISPLAY 0.680851 (4590 3460);
PAINT MONO (4590 3460);
FORCEPROP 0 LASTPIN (4600 3500) $PN 264
J 2
(4590 3510);
DISPLAY 0.680851 (4590 3510);
PAINT MONO (4590 3510);
FORCEPROP 0 LASTPIN (4600 3550) $PN 266
J 2
(4590 3560);
DISPLAY 0.680851 (4590 3560);
PAINT MONO (4590 3560);
FORCEPROP 0 LASTPIN (4600 3600) $PN 268
J 2
(4590 3610);
DISPLAY 0.680851 (4590 3610);
PAINT MONO (4590 3610);
FORCEPROP 0 LASTPIN (4600 3650) $PN 270
J 2
(4590 3660);
DISPLAY 0.680851 (4590 3660);
PAINT MONO (4590 3660);
FORCEPROP 0 LASTPIN (4600 3700) $PN 273
J 2
(4590 3710);
DISPLAY 0.680851 (4590 3710);
PAINT MONO (4590 3710);
FORCEPROP 0 LASTPIN (4600 3750) $PN 275
J 2
(4590 3760);
DISPLAY 0.680851 (4590 3760);
PAINT MONO (4590 3760);
FORCEPROP 0 LASTPIN (4600 3800) $PN 277
J 2
(4590 3810);
DISPLAY 0.680851 (4590 3810);
PAINT MONO (4590 3810);
FORCEPROP 0 LASTPIN (4600 3850) $PN 279
J 2
(4590 3860);
DISPLAY 0.680851 (4590 3860);
PAINT MONO (4590 3860);
FORCEPROP 0 LASTPIN (4600 3900) $PN 281
J 2
(4590 3910);
DISPLAY 0.680851 (4590 3910);
PAINT MONO (4590 3910);
FORCEPROP 0 LASTPIN (4600 3950) $PN 284
J 2
(4590 3960);
DISPLAY 0.680851 (4590 3960);
PAINT MONO (4590 3960);
FORCEPROP 0 LASTPIN (4600 4000) $PN 286
J 2
(4590 4010);
DISPLAY 0.680851 (4590 4010);
PAINT MONO (4590 4010);
FORCEPROP 0 LASTPIN (4600 4050) $PN 288
J 2
(4590 4060);
DISPLAY 0.680851 (4590 4060);
PAINT MONO (4590 4060);
FORCEPROP 1 LAST NEEDS_NO_SIZE TRUE
J 0
(5200 2575);
DISPLAY 0.723404 (5200 2575);
PAINT GREEN (5200 2575);
DISPLAY INVISIBLE (5200 2575);
FORCEPROP 1 LAST CDS_LMAN_SYM_OUTLINE -450,1775,450,-1775
J 0
(5200 2575);
DISPLAY 0.468085 (5200 2575);
PAINT GREEN (5200 2575);
DISPLAY INVISIBLE (5200 2575);
FORCEPROP 2 LAST CDS_LIB pure_quanta
J 0
(5200 2575);
DISPLAY INVISIBLE (5200 2575);
FORCEPROP 2 LAST CDS_LOCATION J2
J 0
(4750 4700);
DISPLAY 1.021277 (4750 4700);
DISPLAY INVISIBLE (4750 4700);
FORCEPROP 0 LAST $SEC 3
J 0
(4750 4700);
DISPLAY 0.680851 (4750 4700);
PAINT MONO (4750 4700);
DISPLAY INVISIBLE (4750 4700);
FORCEPROP 2 LAST CDS_SEC 3
J 0
(4750 4700);
DISPLAY 1.021277 (4750 4700);
DISPLAY INVISIBLE (4750 4700);
FORCEPROP 1 LAST PATH I179
J 0
(5200 2575);
DISPLAY 0.723404 (5200 2575);
PAINT GREEN (5200 2575);
DISPLAY INVISIBLE (5200 2575);
FORCEADD OFFPAGE..1
(-2575 3200);
FORCEPROP 2 LAST $XR0 20 
J 0
(-2826 3200);
DISPLAY 0.638298 (-2826 3200);
PAINT MONO (-2826 3200);
FORCEPROP 2 LAST CDS_LIB standard
J 0
(-2575 3200);
PAINT MONO (-2575 3200);
DISPLAY INVISIBLE (-2575 3200);
FORCEPROP 1 LAST OFFPAGE TRUE
J 0
(-2250 3075);
DISPLAY 0.872340 (-2250 3075);
DISPLAY INVISIBLE (-2250 3075);
FORCEPROP 1 LAST COMMENT_BODY TRUE
J 0
(-2450 3100);
DISPLAY 0.872340 (-2450 3100);
PAINT GREEN (-2450 3100);
DISPLAY INVISIBLE (-2450 3100);
FORCEPROP 2 LAST PATH I18
J 0
(-2525 3275);
DISPLAY 1.021277 (-2525 3275);
DISPLAY INVISIBLE (-2525 3275);
FORCEADD OFFPAGE..3
R 2
(-2575 1350);
FORCEPROP 2 LAST $XR0 114 
J 0
(-2855 1350);
DISPLAY 0.638298 (-2855 1350);
PAINT MONO (-2855 1350);
FORCEPROP 2 LAST CDS_LIB standard
J 0
(-2575 1350);
PAINT MONO (-2575 1350);
DISPLAY INVISIBLE (-2575 1350);
FORCEPROP 1 LAST OFFPAGE TRUE
J 2
(-2900 1225);
DISPLAY 0.872340 (-2900 1225);
DISPLAY INVISIBLE (-2900 1225);
FORCEPROP 1 LAST COMMENT_BODY TRUE
J 2
(-2525 1250);
DISPLAY 0.872340 (-2525 1250);
PAINT GREEN (-2525 1250);
DISPLAY INVISIBLE (-2525 1250);
FORCEPROP 2 LAST PATH I180
J 0
(-2525 1425);
DISPLAY 1.021277 (-2525 1425);
DISPLAY INVISIBLE (-2525 1425);
FORCEADD SCONN288_ADR50017P087CC..2
(1825 3200);
FORCEPROP 1 LAST PART_NUMBER DFHST8FS460
J 0
(1220 4488);
DISPLAY 0.723404 (1220 4488);
PAINT GREEN (1220 4488);
DISPLAY INVISIBLE (1220 4488);
FORCEPROP 1 LAST MATERIAL IO
J 0
(1220 4361);
DISPLAY 0.723404 (1220 4361);
PAINT GREEN (1220 4361);
FORCEPROP 2 LAST PART_TYPE SMLF
J 0
(1225 4725);
DISPLAY 1.021277 (1225 4725);
FORCEPROP 2 LAST VALUE SCONN288_ADR50017-P087CC
J 0
(1225 4675);
DISPLAY 1.021277 (1225 4675);
FORCEPROP 1 LAST LOCATION J2
J 0
(1220 4635);
DISPLAY 0.723404 (1220 4635);
PAINT GREEN (1220 4635);
FORCEPROP 0 LASTPIN (2575 3250) $PN 12
J 0
(2585 3260);
DISPLAY 0.680851 (2585 3260);
PAINT MONO (2585 3260);
FORCEPROP 0 LASTPIN (2575 3300) $PN 11
J 0
(2585 3310);
DISPLAY 0.680851 (2585 3310);
PAINT MONO (2585 3310);
FORCEPROP 0 LASTPIN (2575 2200) $PN 105
J 0
(2585 2210);
DISPLAY 0.680851 (2585 2210);
PAINT MONO (2585 2210);
FORCEPROP 0 LASTPIN (2575 2250) $PN 104
J 0
(2585 2260);
DISPLAY 0.680851 (2585 2260);
PAINT MONO (2585 2260);
FORCEPROP 0 LASTPIN (2575 3350) $PN 23
J 0
(2585 3360);
DISPLAY 0.680851 (2585 3360);
PAINT MONO (2585 3360);
FORCEPROP 0 LASTPIN (2575 3400) $PN 22
J 0
(2585 3410);
DISPLAY 0.680851 (2585 3410);
PAINT MONO (2585 3410);
FORCEPROP 0 LASTPIN (2575 2300) $PN 116
J 0
(2585 2310);
DISPLAY 0.680851 (2585 2310);
PAINT MONO (2585 2310);
FORCEPROP 0 LASTPIN (2575 2350) $PN 115
J 0
(2585 2360);
DISPLAY 0.680851 (2585 2360);
PAINT MONO (2585 2360);
FORCEPROP 0 LASTPIN (2575 3450) $PN 34
J 0
(2585 3460);
DISPLAY 0.680851 (2585 3460);
PAINT MONO (2585 3460);
FORCEPROP 0 LASTPIN (2575 3500) $PN 33
J 0
(2585 3510);
DISPLAY 0.680851 (2585 3510);
PAINT MONO (2585 3510);
FORCEPROP 0 LASTPIN (2575 2400) $PN 127
J 0
(2585 2410);
DISPLAY 0.680851 (2585 2410);
PAINT MONO (2585 2410);
FORCEPROP 0 LASTPIN (2575 2450) $PN 126
J 0
(2585 2460);
DISPLAY 0.680851 (2585 2460);
PAINT MONO (2585 2460);
FORCEPROP 0 LASTPIN (2575 3550) $PN 45
J 0
(2585 3560);
DISPLAY 0.680851 (2585 3560);
PAINT MONO (2585 3560);
FORCEPROP 0 LASTPIN (2575 3600) $PN 44
J 0
(2585 3610);
DISPLAY 0.680851 (2585 3610);
PAINT MONO (2585 3610);
FORCEPROP 0 LASTPIN (2575 2500) $PN 138
J 0
(2585 2510);
DISPLAY 0.680851 (2585 2510);
PAINT MONO (2585 2510);
FORCEPROP 0 LASTPIN (2575 2550) $PN 137
J 0
(2585 2560);
DISPLAY 0.680851 (2585 2560);
PAINT MONO (2585 2560);
FORCEPROP 0 LASTPIN (2575 3650) $PN 56
J 0
(2585 3660);
DISPLAY 0.680851 (2585 3660);
PAINT MONO (2585 3660);
FORCEPROP 0 LASTPIN (2575 3700) $PN 55
J 0
(2585 3710);
DISPLAY 0.680851 (2585 3710);
PAINT MONO (2585 3710);
FORCEPROP 0 LASTPIN (2575 2600) $PN 238
J 0
(2585 2610);
DISPLAY 0.680851 (2585 2610);
PAINT MONO (2585 2610);
FORCEPROP 0 LASTPIN (2575 2650) $PN 239
J 0
(2585 2660);
DISPLAY 0.680851 (2585 2660);
PAINT MONO (2585 2660);
FORCEPROP 0 LASTPIN (2575 3750) $PN 156
J 0
(2585 3760);
DISPLAY 0.680851 (2585 3760);
PAINT MONO (2585 3760);
FORCEPROP 0 LASTPIN (2575 3800) $PN 157
J 0
(2585 3810);
DISPLAY 0.680851 (2585 3810);
PAINT MONO (2585 3810);
FORCEPROP 0 LASTPIN (2575 2700) $PN 249
J 0
(2585 2710);
DISPLAY 0.680851 (2585 2710);
PAINT MONO (2585 2710);
FORCEPROP 0 LASTPIN (2575 2750) $PN 250
J 0
(2585 2760);
DISPLAY 0.680851 (2585 2760);
PAINT MONO (2585 2760);
FORCEPROP 0 LASTPIN (2575 3850) $PN 167
J 0
(2585 3860);
DISPLAY 0.680851 (2585 3860);
PAINT MONO (2585 3860);
FORCEPROP 0 LASTPIN (2575 3900) $PN 168
J 0
(2585 3910);
DISPLAY 0.680851 (2585 3910);
PAINT MONO (2585 3910);
FORCEPROP 0 LASTPIN (2575 2800) $PN 260
J 0
(2585 2810);
DISPLAY 0.680851 (2585 2810);
PAINT MONO (2585 2810);
FORCEPROP 0 LASTPIN (2575 2850) $PN 261
J 0
(2585 2860);
DISPLAY 0.680851 (2585 2860);
PAINT MONO (2585 2860);
FORCEPROP 0 LASTPIN (2575 3950) $PN 178
J 0
(2585 3960);
DISPLAY 0.680851 (2585 3960);
PAINT MONO (2585 3960);
FORCEPROP 0 LASTPIN (2575 4000) $PN 179
J 0
(2585 4010);
DISPLAY 0.680851 (2585 4010);
PAINT MONO (2585 4010);
FORCEPROP 0 LASTPIN (2575 2900) $PN 271
J 0
(2585 2910);
DISPLAY 0.680851 (2585 2910);
PAINT MONO (2585 2910);
FORCEPROP 0 LASTPIN (2575 2950) $PN 272
J 0
(2585 2960);
DISPLAY 0.680851 (2585 2960);
PAINT MONO (2585 2960);
FORCEPROP 0 LASTPIN (2575 4050) $PN 189
J 0
(2585 4060);
DISPLAY 0.680851 (2585 4060);
PAINT MONO (2585 4060);
FORCEPROP 0 LASTPIN (2575 4100) $PN 190
J 0
(2585 4110);
DISPLAY 0.680851 (2585 4110);
PAINT MONO (2585 4110);
FORCEPROP 0 LASTPIN (2575 3000) $PN 282
J 0
(2585 3010);
DISPLAY 0.680851 (2585 3010);
PAINT MONO (2585 3010);
FORCEPROP 0 LASTPIN (2575 3050) $PN 283
J 0
(2585 3060);
DISPLAY 0.680851 (2585 3060);
PAINT MONO (2585 3060);
FORCEPROP 0 LASTPIN (2575 4150) $PN 200
J 0
(2585 4160);
DISPLAY 0.680851 (2585 4160);
PAINT MONO (2585 4160);
FORCEPROP 0 LASTPIN (2575 4200) $PN 201
J 0
(2585 4210);
DISPLAY 0.680851 (2585 4210);
PAINT MONO (2585 4210);
FORCEPROP 0 LASTPIN (2575 3100) $PN 94
J 0
(2585 3110);
DISPLAY 0.680851 (2585 3110);
PAINT MONO (2585 3110);
FORCEPROP 0 LASTPIN (2575 3150) $PN 93
J 0
(2585 3160);
DISPLAY 0.680851 (2585 3160);
PAINT MONO (2585 3160);
FORCEPROP 2 LAST CDS_LIB pure_quanta
J 0
(1825 3200);
DISPLAY INVISIBLE (1825 3200);
FORCEPROP 1 LAST NEEDS_NO_SIZE TRUE
J 0
(1825 3200);
DISPLAY 0.723404 (1825 3200);
PAINT GREEN (1825 3200);
DISPLAY INVISIBLE (1825 3200);
FORCEPROP 1 LAST CDS_LMAN_SYM_OUTLINE -600,1150,600,-1150
J 0
(1825 3200);
DISPLAY 0.468085 (1825 3200);
PAINT GREEN (1825 3200);
DISPLAY INVISIBLE (1825 3200);
FORCEPROP 0 LAST $SEC 2
J 0
(1225 4775);
DISPLAY 0.680851 (1225 4775);
PAINT MONO (1225 4775);
DISPLAY INVISIBLE (1225 4775);
FORCEPROP 0 LAST CDS_SEC 2
J 0
(1225 4775);
DISPLAY 1.021277 (1225 4775);
DISPLAY INVISIBLE (1225 4775);
FORCEPROP 1 LAST PATH I181
J 0
(1825 3200);
DISPLAY 0.723404 (1825 3200);
PAINT GREEN (1825 3200);
DISPLAY INVISIBLE (1825 3200);
FORCEADD Q_RES..1
(-2650 1500);
FORCEPROP 1 LAST PART_NUMBER CS04992FB07
J 0
(-2550 1475);
DISPLAY 0.404255 (-2550 1475);
DISPLAY INVISIBLE (-2550 1475);
FORCEPROP 1 LAST VALUE 49.9
J 2
(-2425 1500);
DISPLAY 0.510638 (-2425 1500);
FORCEPROP 1 LAST MATERIAL CHIP
J 0
(-2500 1525);
DISPLAY 0.404255 (-2500 1525);
FORCEPROP 1 LAST $LOCATION R3876
J 0
(-2850 1500);
DISPLAY 0.638298 (-2850 1500);
FORCEPROP 1 LASTPIN (-2750 1500) $PN 1
J 0
(-2738 1512);
DISPLAY 0.787234 (-2738 1512);
PAINT MONO (-2738 1512);
FORCEPROP 1 LASTPIN (-2550 1500) $PN 2
J 0
(-2588 1512);
DISPLAY 0.787234 (-2588 1512);
PAINT MONO (-2588 1512);
FORCEPROP 2 LAST CDS_LIB pure_quanta
J 0
(-2650 1500);
DISPLAY INVISIBLE (-2650 1500);
FORCEPROP 1 LAST PACK_TYPE 0402LF
J 0
(-2350 1500);
DISPLAY 0.510638 (-2350 1500);
DISPLAY INVISIBLE (-2350 1500);
FORCEPROP 1 LAST TOLERANCE 1%
J 0
(-2425 1500);
DISPLAY 0.510638 (-2425 1500);
DISPLAY INVISIBLE (-2425 1500);
FORCEPROP 1 LAST WATTAGE 1/16W
J 2
(-2350 1450);
DISPLAY 0.404255 (-2350 1450);
DISPLAY INVISIBLE (-2350 1450);
FORCEPROP 0 LAST CDS_LOCATION R3876
J 0
(-2775 1550);
DISPLAY 1.021277 (-2775 1550);
DISPLAY INVISIBLE (-2775 1550);
FORCEPROP 0 LAST $SEC 1
J 0
(-2775 1550);
DISPLAY 0.680851 (-2775 1550);
PAINT MONO (-2775 1550);
DISPLAY INVISIBLE (-2775 1550);
FORCEPROP 0 LAST CDS_SEC 1
J 0
(-2775 1550);
DISPLAY 1.021277 (-2775 1550);
DISPLAY INVISIBLE (-2775 1550);
FORCEPROP 1 LAST PATH I182
J 0
(-2700 1650);
DISPLAY 0.978723 (-2700 1650);
PAINT WHITE (-2700 1650);
DISPLAY INVISIBLE (-2700 1650);
FORCEADD OFFPAGE..1
(-1550 1450);
FORCEPROP 2 LAST $XR7 89 
J 0
(-2432 1450);
DISPLAY 0.638298 (-2432 1450);
PAINT MONO (-2432 1450);
FORCEPROP 2 LAST $XR6 88 
J 0
(-2342 1450);
DISPLAY 0.638298 (-2342 1450);
PAINT MONO (-2342 1450);
FORCEPROP 2 LAST $XR5 87 
J 0
(-2252 1450);
DISPLAY 0.638298 (-2252 1450);
PAINT MONO (-2252 1450);
FORCEPROP 2 LAST $XR4 86 
J 0
(-2162 1450);
DISPLAY 0.638298 (-2162 1450);
PAINT MONO (-2162 1450);
FORCEPROP 2 LAST $XR3 85 
J 0
(-2072 1450);
DISPLAY 0.638298 (-2072 1450);
PAINT MONO (-2072 1450);
FORCEPROP 2 LAST $XR2 84 
J 0
(-1982 1450);
DISPLAY 0.638298 (-1982 1450);
PAINT MONO (-1982 1450);
FORCEPROP 2 LAST $XR1 82 
J 0
(-1892 1450);
DISPLAY 0.638298 (-1892 1450);
PAINT MONO (-1892 1450);
FORCEPROP 2 LAST $XR0 229 
J 0
(-1802 1450);
DISPLAY 0.638298 (-1802 1450);
PAINT MONO (-1802 1450);
FORCEPROP 2 LAST CDS_LIB standard
J 0
(-1550 1450);
PAINT MONO (-1550 1450);
DISPLAY INVISIBLE (-1550 1450);
FORCEPROP 1 LAST OFFPAGE TRUE
J 0
(-1225 1325);
DISPLAY 0.872340 (-1225 1325);
DISPLAY INVISIBLE (-1225 1325);
FORCEPROP 1 LAST COMMENT_BODY TRUE
J 0
(-1425 1350);
DISPLAY 0.872340 (-1425 1350);
PAINT GREEN (-1425 1350);
DISPLAY INVISIBLE (-1425 1350);
FORCEPROP 2 LAST PATH I183
J 2
(-2475 1500);
DISPLAY 1.021277 (-2475 1500);
DISPLAY INVISIBLE (-2475 1500);
FORCEADD OFFPAGE..1
(-2575 3100);
FORCEPROP 2 LAST $XR0 20 
J 0
(-2826 3100);
DISPLAY 0.638298 (-2826 3100);
PAINT MONO (-2826 3100);
FORCEPROP 2 LAST CDS_LIB standard
J 0
(-2575 3100);
PAINT MONO (-2575 3100);
DISPLAY INVISIBLE (-2575 3100);
FORCEPROP 1 LAST OFFPAGE TRUE
J 0
(-2250 2975);
DISPLAY 0.872340 (-2250 2975);
DISPLAY INVISIBLE (-2250 2975);
FORCEPROP 1 LAST COMMENT_BODY TRUE
J 0
(-2450 3000);
DISPLAY 0.872340 (-2450 3000);
PAINT GREEN (-2450 3000);
DISPLAY INVISIBLE (-2450 3000);
FORCEPROP 2 LAST PATH I19
J 0
(-2525 3175);
DISPLAY 1.021277 (-2525 3175);
DISPLAY INVISIBLE (-2525 3175);
FORCEADD OFFPAGE..2
R 2
(-2575 250);
FORCEPROP 2 LAST $XR0 83 
J 0
(-2799 250);
DISPLAY 0.638298 (-2799 250);
PAINT MONO (-2799 250);
FORCEPROP 2 LAST CDS_LIB standard
J 0
(-2575 250);
PAINT MONO (-2575 250);
DISPLAY INVISIBLE (-2575 250);
FORCEPROP 1 LAST OFFPAGE TRUE
J 2
(-2900 125);
DISPLAY 0.872340 (-2900 125);
DISPLAY INVISIBLE (-2900 125);
FORCEPROP 1 LAST COMMENT_BODY TRUE
J 2
(-2530 155);
DISPLAY 0.872340 (-2530 155);
PAINT GREEN (-2530 155);
DISPLAY INVISIBLE (-2530 155);
FORCEPROP 2 LAST PATH I2
J 0
(-2525 325);
DISPLAY 1.021277 (-2525 325);
DISPLAY INVISIBLE (-2525 325);
FORCEADD OFFPAGE..1
(-2575 3250);
FORCEPROP 2 LAST $XR0 20 
J 0
(-2826 3250);
DISPLAY 0.638298 (-2826 3250);
PAINT MONO (-2826 3250);
FORCEPROP 2 LAST CDS_LIB standard
J 0
(-2575 3250);
PAINT MONO (-2575 3250);
DISPLAY INVISIBLE (-2575 3250);
FORCEPROP 1 LAST OFFPAGE TRUE
J 0
(-2250 3125);
DISPLAY 0.872340 (-2250 3125);
DISPLAY INVISIBLE (-2250 3125);
FORCEPROP 1 LAST COMMENT_BODY TRUE
J 0
(-2450 3150);
DISPLAY 0.872340 (-2450 3150);
PAINT GREEN (-2450 3150);
DISPLAY INVISIBLE (-2450 3150);
FORCEPROP 2 LAST PATH I20
J 0
(-2525 3325);
DISPLAY 1.021277 (-2525 3325);
DISPLAY INVISIBLE (-2525 3325);
FORCEADD OFFPAGE..1
(-2575 3400);
FORCEPROP 2 LAST $XR1 82 
J 0
(-2916 3400);
DISPLAY 0.638298 (-2916 3400);
PAINT MONO (-2916 3400);
FORCEPROP 2 LAST $XR0 20 
J 0
(-2826 3400);
DISPLAY 0.638298 (-2826 3400);
PAINT MONO (-2826 3400);
FORCEPROP 2 LAST CDS_LIB standard
J 0
(-2575 3400);
PAINT MONO (-2575 3400);
DISPLAY INVISIBLE (-2575 3400);
FORCEPROP 1 LAST OFFPAGE TRUE
J 0
(-2250 3275);
DISPLAY 0.872340 (-2250 3275);
DISPLAY INVISIBLE (-2250 3275);
FORCEPROP 1 LAST COMMENT_BODY TRUE
J 0
(-2450 3300);
DISPLAY 0.872340 (-2450 3300);
PAINT GREEN (-2450 3300);
DISPLAY INVISIBLE (-2450 3300);
FORCEPROP 2 LAST PATH I21
J 0
(-2525 3475);
DISPLAY 1.021277 (-2525 3475);
DISPLAY INVISIBLE (-2525 3475);
FORCEADD OFFPAGE..1
(-2575 3350);
FORCEPROP 2 LAST $XR1 82 
J 0
(-2916 3350);
DISPLAY 0.638298 (-2916 3350);
PAINT MONO (-2916 3350);
FORCEPROP 2 LAST $XR0 20 
J 0
(-2826 3350);
DISPLAY 0.638298 (-2826 3350);
PAINT MONO (-2826 3350);
FORCEPROP 2 LAST CDS_LIB standard
J 0
(-2575 3350);
PAINT MONO (-2575 3350);
DISPLAY INVISIBLE (-2575 3350);
FORCEPROP 1 LAST OFFPAGE TRUE
J 0
(-2250 3225);
DISPLAY 0.872340 (-2250 3225);
DISPLAY INVISIBLE (-2250 3225);
FORCEPROP 1 LAST COMMENT_BODY TRUE
J 0
(-2450 3250);
DISPLAY 0.872340 (-2450 3250);
PAINT GREEN (-2450 3250);
DISPLAY INVISIBLE (-2450 3250);
FORCEPROP 2 LAST PATH I22
J 0
(-2525 3425);
DISPLAY 1.021277 (-2525 3425);
DISPLAY INVISIBLE (-2525 3425);
FORCEADD OFFPAGE..1
(-2575 3825);
FORCEPROP 2 LAST $XR1 82 
J 0
(-2916 3825);
DISPLAY 0.638298 (-2916 3825);
PAINT MONO (-2916 3825);
FORCEPROP 2 LAST $XR0 20 
J 0
(-2826 3825);
DISPLAY 0.638298 (-2826 3825);
PAINT MONO (-2826 3825);
FORCEPROP 2 LAST CDS_LIB standard
J 0
(-2575 3825);
PAINT MONO (-2575 3825);
DISPLAY INVISIBLE (-2575 3825);
FORCEPROP 1 LAST OFFPAGE TRUE
J 0
(-2250 3700);
DISPLAY 0.872340 (-2250 3700);
DISPLAY INVISIBLE (-2250 3700);
FORCEPROP 1 LAST COMMENT_BODY TRUE
J 0
(-2450 3725);
DISPLAY 0.872340 (-2450 3725);
PAINT GREEN (-2450 3725);
DISPLAY INVISIBLE (-2450 3725);
FORCEPROP 2 LAST PATH I23
J 0
(-2525 3900);
DISPLAY 1.021277 (-2525 3900);
DISPLAY INVISIBLE (-2525 3900);
FORCEADD TAP..1
R 2
(-1650 2050);
FORCEPROP 3 LASTPIN (-1600 2050) SIG_NAME M_A_CPU0_SB_CB<1>
J 0
(-1590 2060);
DISPLAY 0.659574 (-1590 2060);
PAINT MONO (-1590 2060);
DISPLAY INVISIBLE (-1590 2060);
FORCEPROP 1 LASTPIN (-1600 2050) BN 1
J 2
(-1588 2058);
DISPLAY 0.680851 (-1588 2058);
PAINT GREEN (-1588 2058);
FORCEPROP 2 LAST CDS_LIB standard
J 0
(-1650 2050);
DISPLAY INVISIBLE (-1650 2050);
FORCEPROP 1 LAST BODY_TYPE PLUMBING
J 2
(-1650 2100);
DISPLAY 0.872340 (-1650 2100);
PAINT GREEN (-1650 2100);
DISPLAY INVISIBLE (-1650 2100);
FORCEPROP 1 LAST HDL_TAP TRUE
J 2
(-1975 1925);
DISPLAY 0.872340 (-1975 1925);
DISPLAY INVISIBLE (-1975 1925);
FORCEPROP 1 LAST PATH I24
J 2
(-1648 2050);
DISPLAY 0.872340 (-1648 2050);
PAINT GREEN (-1648 2050);
DISPLAY INVISIBLE (-1648 2050);
FORCEADD TAP..1
R 2
(-1650 2000);
FORCEPROP 3 LASTPIN (-1600 2000) SIG_NAME M_A_CPU0_SB_CB<0>
J 0
(-1590 2010);
DISPLAY 0.659574 (-1590 2010);
PAINT MONO (-1590 2010);
DISPLAY INVISIBLE (-1590 2010);
FORCEPROP 1 LASTPIN (-1600 2000) BN 0
J 2
(-1588 2008);
DISPLAY 0.680851 (-1588 2008);
PAINT GREEN (-1588 2008);
FORCEPROP 2 LAST CDS_LIB standard
J 0
(-1650 2000);
PAINT MONO (-1650 2000);
DISPLAY INVISIBLE (-1650 2000);
FORCEPROP 1 LAST BODY_TYPE PLUMBING
J 2
(-1650 2050);
DISPLAY 0.872340 (-1650 2050);
PAINT GREEN (-1650 2050);
DISPLAY INVISIBLE (-1650 2050);
FORCEPROP 1 LAST HDL_TAP TRUE
J 2
(-1975 1875);
DISPLAY 0.872340 (-1975 1875);
DISPLAY INVISIBLE (-1975 1875);
FORCEPROP 1 LAST PATH I25
J 2
(-1648 2000);
DISPLAY 0.872340 (-1648 2000);
PAINT GREEN (-1648 2000);
DISPLAY INVISIBLE (-1648 2000);
FORCEADD TAP..1
R 2
(-1650 2100);
FORCEPROP 3 LASTPIN (-1600 2100) SIG_NAME M_A_CPU0_SB_CB<2>
J 0
(-1590 2110);
DISPLAY 0.659574 (-1590 2110);
PAINT MONO (-1590 2110);
DISPLAY INVISIBLE (-1590 2110);
FORCEPROP 1 LASTPIN (-1600 2100) BN 2
J 2
(-1588 2108);
DISPLAY 0.680851 (-1588 2108);
PAINT GREEN (-1588 2108);
FORCEPROP 2 LAST CDS_LIB standard
J 0
(-1650 2100);
DISPLAY INVISIBLE (-1650 2100);
FORCEPROP 1 LAST BODY_TYPE PLUMBING
J 2
(-1650 2150);
DISPLAY 0.872340 (-1650 2150);
PAINT GREEN (-1650 2150);
DISPLAY INVISIBLE (-1650 2150);
FORCEPROP 1 LAST HDL_TAP TRUE
J 2
(-1975 1975);
DISPLAY 0.872340 (-1975 1975);
DISPLAY INVISIBLE (-1975 1975);
FORCEPROP 1 LAST PATH I26
J 2
(-1648 2100);
DISPLAY 0.872340 (-1648 2100);
PAINT GREEN (-1648 2100);
DISPLAY INVISIBLE (-1648 2100);
FORCEADD TAP..1
R 2
(-1650 2150);
FORCEPROP 3 LASTPIN (-1600 2150) SIG_NAME M_A_CPU0_SB_CB<3>
J 0
(-1590 2160);
DISPLAY 0.659574 (-1590 2160);
PAINT MONO (-1590 2160);
DISPLAY INVISIBLE (-1590 2160);
FORCEPROP 1 LASTPIN (-1600 2150) BN 3
J 2
(-1588 2158);
DISPLAY 0.680851 (-1588 2158);
PAINT GREEN (-1588 2158);
FORCEPROP 2 LAST CDS_LIB standard
J 0
(-1650 2150);
DISPLAY INVISIBLE (-1650 2150);
FORCEPROP 1 LAST BODY_TYPE PLUMBING
J 2
(-1650 2200);
DISPLAY 0.872340 (-1650 2200);
PAINT GREEN (-1650 2200);
DISPLAY INVISIBLE (-1650 2200);
FORCEPROP 1 LAST HDL_TAP TRUE
J 2
(-1975 2025);
DISPLAY 0.872340 (-1975 2025);
DISPLAY INVISIBLE (-1975 2025);
FORCEPROP 1 LAST PATH I27
J 2
(-1648 2150);
DISPLAY 0.872340 (-1648 2150);
PAINT GREEN (-1648 2150);
DISPLAY INVISIBLE (-1648 2150);
FORCEADD TAP..1
R 2
(-1650 2200);
FORCEPROP 3 LASTPIN (-1600 2200) SIG_NAME M_A_CPU0_SB_CB<4>
J 0
(-1590 2210);
DISPLAY 0.659574 (-1590 2210);
PAINT MONO (-1590 2210);
DISPLAY INVISIBLE (-1590 2210);
FORCEPROP 1 LASTPIN (-1600 2200) BN 4
J 2
(-1588 2208);
DISPLAY 0.680851 (-1588 2208);
PAINT GREEN (-1588 2208);
FORCEPROP 2 LAST CDS_LIB standard
J 0
(-1650 2200);
DISPLAY INVISIBLE (-1650 2200);
FORCEPROP 1 LAST BODY_TYPE PLUMBING
J 2
(-1650 2250);
DISPLAY 0.872340 (-1650 2250);
PAINT GREEN (-1650 2250);
DISPLAY INVISIBLE (-1650 2250);
FORCEPROP 1 LAST HDL_TAP TRUE
J 2
(-1975 2075);
DISPLAY 0.872340 (-1975 2075);
DISPLAY INVISIBLE (-1975 2075);
FORCEPROP 1 LAST PATH I28
J 2
(-1648 2200);
DISPLAY 0.872340 (-1648 2200);
PAINT GREEN (-1648 2200);
DISPLAY INVISIBLE (-1648 2200);
FORCEADD TAP..1
R 2
(-1650 2300);
FORCEPROP 3 LASTPIN (-1600 2300) SIG_NAME M_A_CPU0_SB_CB<6>
J 0
(-1590 2310);
DISPLAY 0.659574 (-1590 2310);
PAINT MONO (-1590 2310);
DISPLAY INVISIBLE (-1590 2310);
FORCEPROP 1 LASTPIN (-1600 2300) BN 6
J 2
(-1588 2308);
DISPLAY 0.680851 (-1588 2308);
PAINT GREEN (-1588 2308);
FORCEPROP 2 LAST CDS_LIB standard
J 0
(-1650 2300);
DISPLAY INVISIBLE (-1650 2300);
FORCEPROP 1 LAST BODY_TYPE PLUMBING
J 2
(-1650 2350);
DISPLAY 0.872340 (-1650 2350);
PAINT GREEN (-1650 2350);
DISPLAY INVISIBLE (-1650 2350);
FORCEPROP 1 LAST HDL_TAP TRUE
J 2
(-1975 2175);
DISPLAY 0.872340 (-1975 2175);
DISPLAY INVISIBLE (-1975 2175);
FORCEPROP 1 LAST PATH I29
J 2
(-1648 2300);
DISPLAY 0.872340 (-1648 2300);
PAINT GREEN (-1648 2300);
DISPLAY INVISIBLE (-1648 2300);
FORCEADD OFFPAGE..2
R 2
(-2575 800);
FORCEPROP 2 LAST $XR0 20 
J 0
(-2799 800);
DISPLAY 0.638298 (-2799 800);
PAINT MONO (-2799 800);
FORCEPROP 2 LAST CDS_LIB standard
J 0
(-2575 800);
PAINT MONO (-2575 800);
DISPLAY INVISIBLE (-2575 800);
FORCEPROP 1 LAST OFFPAGE TRUE
J 2
(-2900 675);
DISPLAY 0.872340 (-2900 675);
DISPLAY INVISIBLE (-2900 675);
FORCEPROP 1 LAST COMMENT_BODY TRUE
J 2
(-2530 705);
DISPLAY 0.872340 (-2530 705);
PAINT GREEN (-2530 705);
DISPLAY INVISIBLE (-2530 705);
FORCEPROP 2 LAST PATH I3
J 0
(-2525 875);
DISPLAY 1.021277 (-2525 875);
DISPLAY INVISIBLE (-2525 875);
FORCEADD TAP..1
R 2
(-1650 2250);
FORCEPROP 3 LASTPIN (-1600 2250) SIG_NAME M_A_CPU0_SB_CB<5>
J 0
(-1590 2260);
DISPLAY 0.659574 (-1590 2260);
PAINT MONO (-1590 2260);
DISPLAY INVISIBLE (-1590 2260);
FORCEPROP 1 LASTPIN (-1600 2250) BN 5
J 2
(-1588 2258);
DISPLAY 0.680851 (-1588 2258);
PAINT GREEN (-1588 2258);
FORCEPROP 2 LAST CDS_LIB standard
J 0
(-1650 2250);
DISPLAY INVISIBLE (-1650 2250);
FORCEPROP 1 LAST BODY_TYPE PLUMBING
J 2
(-1650 2300);
DISPLAY 0.872340 (-1650 2300);
PAINT GREEN (-1650 2300);
DISPLAY INVISIBLE (-1650 2300);
FORCEPROP 1 LAST HDL_TAP TRUE
J 2
(-1975 2125);
DISPLAY 0.872340 (-1975 2125);
DISPLAY INVISIBLE (-1975 2125);
FORCEPROP 1 LAST PATH I30
J 2
(-1648 2250);
DISPLAY 0.872340 (-1648 2250);
PAINT GREEN (-1648 2250);
DISPLAY INVISIBLE (-1648 2250);
FORCEADD TAP..1
R 2
(-1650 2450);
FORCEPROP 3 LASTPIN (-1600 2450) SIG_NAME M_A_CPU0_SA_CB<0>
J 0
(-1590 2460);
DISPLAY 0.659574 (-1590 2460);
PAINT MONO (-1590 2460);
DISPLAY INVISIBLE (-1590 2460);
FORCEPROP 1 LASTPIN (-1600 2450) BN 0
J 2
(-1588 2458);
DISPLAY 0.680851 (-1588 2458);
PAINT GREEN (-1588 2458);
FORCEPROP 2 LAST CDS_LIB standard
J 0
(-1650 2450);
PAINT MONO (-1650 2450);
DISPLAY INVISIBLE (-1650 2450);
FORCEPROP 1 LAST BODY_TYPE PLUMBING
J 2
(-1650 2500);
DISPLAY 0.872340 (-1650 2500);
PAINT GREEN (-1650 2500);
DISPLAY INVISIBLE (-1650 2500);
FORCEPROP 1 LAST HDL_TAP TRUE
J 2
(-1975 2325);
DISPLAY 0.872340 (-1975 2325);
DISPLAY INVISIBLE (-1975 2325);
FORCEPROP 1 LAST PATH I31
J 2
(-1648 2450);
DISPLAY 0.872340 (-1648 2450);
PAINT GREEN (-1648 2450);
DISPLAY INVISIBLE (-1648 2450);
FORCEADD TAP..1
R 2
(-1650 2350);
FORCEPROP 3 LASTPIN (-1600 2350) SIG_NAME M_A_CPU0_SB_CB<7>
J 0
(-1590 2360);
DISPLAY 0.659574 (-1590 2360);
PAINT MONO (-1590 2360);
DISPLAY INVISIBLE (-1590 2360);
FORCEPROP 1 LASTPIN (-1600 2350) BN 7
J 2
(-1588 2358);
DISPLAY 0.680851 (-1588 2358);
PAINT GREEN (-1588 2358);
FORCEPROP 2 LAST CDS_LIB standard
J 0
(-1650 2350);
DISPLAY INVISIBLE (-1650 2350);
FORCEPROP 1 LAST BODY_TYPE PLUMBING
J 2
(-1650 2400);
DISPLAY 0.872340 (-1650 2400);
PAINT GREEN (-1650 2400);
DISPLAY INVISIBLE (-1650 2400);
FORCEPROP 1 LAST HDL_TAP TRUE
J 2
(-1975 2225);
DISPLAY 0.872340 (-1975 2225);
DISPLAY INVISIBLE (-1975 2225);
FORCEPROP 1 LAST PATH I32
J 2
(-1648 2350);
DISPLAY 0.872340 (-1648 2350);
PAINT GREEN (-1648 2350);
DISPLAY INVISIBLE (-1648 2350);
FORCEADD TAP..1
R 2
(-1650 2500);
FORCEPROP 3 LASTPIN (-1600 2500) SIG_NAME M_A_CPU0_SA_CB<1>
J 0
(-1590 2510);
DISPLAY 0.659574 (-1590 2510);
PAINT MONO (-1590 2510);
DISPLAY INVISIBLE (-1590 2510);
FORCEPROP 1 LASTPIN (-1600 2500) BN 1
J 2
(-1588 2508);
DISPLAY 0.680851 (-1588 2508);
PAINT GREEN (-1588 2508);
FORCEPROP 2 LAST CDS_LIB standard
J 0
(-1650 2500);
DISPLAY INVISIBLE (-1650 2500);
FORCEPROP 1 LAST BODY_TYPE PLUMBING
J 2
(-1650 2550);
DISPLAY 0.872340 (-1650 2550);
PAINT GREEN (-1650 2550);
DISPLAY INVISIBLE (-1650 2550);
FORCEPROP 1 LAST HDL_TAP TRUE
J 2
(-1975 2375);
DISPLAY 0.872340 (-1975 2375);
DISPLAY INVISIBLE (-1975 2375);
FORCEPROP 1 LAST PATH I33
J 2
(-1648 2500);
DISPLAY 0.872340 (-1648 2500);
PAINT GREEN (-1648 2500);
DISPLAY INVISIBLE (-1648 2500);
FORCEADD TAP..1
R 2
(-1650 2550);
FORCEPROP 3 LASTPIN (-1600 2550) SIG_NAME M_A_CPU0_SA_CB<2>
J 0
(-1590 2560);
DISPLAY 0.659574 (-1590 2560);
PAINT MONO (-1590 2560);
DISPLAY INVISIBLE (-1590 2560);
FORCEPROP 1 LASTPIN (-1600 2550) BN 2
J 2
(-1588 2558);
DISPLAY 0.680851 (-1588 2558);
PAINT GREEN (-1588 2558);
FORCEPROP 2 LAST CDS_LIB standard
J 0
(-1650 2550);
DISPLAY INVISIBLE (-1650 2550);
FORCEPROP 1 LAST BODY_TYPE PLUMBING
J 2
(-1650 2600);
DISPLAY 0.872340 (-1650 2600);
PAINT GREEN (-1650 2600);
DISPLAY INVISIBLE (-1650 2600);
FORCEPROP 1 LAST HDL_TAP TRUE
J 2
(-1975 2425);
DISPLAY 0.872340 (-1975 2425);
DISPLAY INVISIBLE (-1975 2425);
FORCEPROP 1 LAST PATH I34
J 2
(-1648 2550);
DISPLAY 0.872340 (-1648 2550);
PAINT GREEN (-1648 2550);
DISPLAY INVISIBLE (-1648 2550);
FORCEADD TAP..1
R 2
(-1650 2650);
FORCEPROP 3 LASTPIN (-1600 2650) SIG_NAME M_A_CPU0_SA_CB<4>
J 0
(-1590 2660);
DISPLAY 0.659574 (-1590 2660);
PAINT MONO (-1590 2660);
DISPLAY INVISIBLE (-1590 2660);
FORCEPROP 1 LASTPIN (-1600 2650) BN 4
J 2
(-1588 2658);
DISPLAY 0.680851 (-1588 2658);
PAINT GREEN (-1588 2658);
FORCEPROP 2 LAST CDS_LIB standard
J 0
(-1650 2650);
DISPLAY INVISIBLE (-1650 2650);
FORCEPROP 1 LAST BODY_TYPE PLUMBING
J 2
(-1650 2700);
DISPLAY 0.872340 (-1650 2700);
PAINT GREEN (-1650 2700);
DISPLAY INVISIBLE (-1650 2700);
FORCEPROP 1 LAST HDL_TAP TRUE
J 2
(-1975 2525);
DISPLAY 0.872340 (-1975 2525);
DISPLAY INVISIBLE (-1975 2525);
FORCEPROP 1 LAST PATH I35
J 2
(-1648 2650);
DISPLAY 0.872340 (-1648 2650);
PAINT GREEN (-1648 2650);
DISPLAY INVISIBLE (-1648 2650);
FORCEADD TAP..1
R 2
(-1650 2600);
FORCEPROP 3 LASTPIN (-1600 2600) SIG_NAME M_A_CPU0_SA_CB<3>
J 0
(-1590 2610);
DISPLAY 0.659574 (-1590 2610);
PAINT MONO (-1590 2610);
DISPLAY INVISIBLE (-1590 2610);
FORCEPROP 1 LASTPIN (-1600 2600) BN 3
J 2
(-1588 2608);
DISPLAY 0.680851 (-1588 2608);
PAINT GREEN (-1588 2608);
FORCEPROP 2 LAST CDS_LIB standard
J 0
(-1650 2600);
DISPLAY INVISIBLE (-1650 2600);
FORCEPROP 1 LAST BODY_TYPE PLUMBING
J 2
(-1650 2650);
DISPLAY 0.872340 (-1650 2650);
PAINT GREEN (-1650 2650);
DISPLAY INVISIBLE (-1650 2650);
FORCEPROP 1 LAST HDL_TAP TRUE
J 2
(-1975 2475);
DISPLAY 0.872340 (-1975 2475);
DISPLAY INVISIBLE (-1975 2475);
FORCEPROP 1 LAST PATH I36
J 2
(-1648 2600);
DISPLAY 0.872340 (-1648 2600);
PAINT GREEN (-1648 2600);
DISPLAY INVISIBLE (-1648 2600);
FORCEADD TAP..1
R 2
(-1650 2700);
FORCEPROP 3 LASTPIN (-1600 2700) SIG_NAME M_A_CPU0_SA_CB<5>
J 0
(-1590 2710);
DISPLAY 0.659574 (-1590 2710);
PAINT MONO (-1590 2710);
DISPLAY INVISIBLE (-1590 2710);
FORCEPROP 1 LASTPIN (-1600 2700) BN 5
J 2
(-1588 2708);
DISPLAY 0.680851 (-1588 2708);
PAINT GREEN (-1588 2708);
FORCEPROP 2 LAST CDS_LIB standard
J 0
(-1650 2700);
DISPLAY INVISIBLE (-1650 2700);
FORCEPROP 1 LAST BODY_TYPE PLUMBING
J 2
(-1650 2750);
DISPLAY 0.872340 (-1650 2750);
PAINT GREEN (-1650 2750);
DISPLAY INVISIBLE (-1650 2750);
FORCEPROP 1 LAST HDL_TAP TRUE
J 2
(-1975 2575);
DISPLAY 0.872340 (-1975 2575);
DISPLAY INVISIBLE (-1975 2575);
FORCEPROP 1 LAST PATH I37
J 2
(-1648 2700);
DISPLAY 0.872340 (-1648 2700);
PAINT GREEN (-1648 2700);
DISPLAY INVISIBLE (-1648 2700);
FORCEADD TAP..1
R 2
(-1650 2800);
FORCEPROP 3 LASTPIN (-1600 2800) SIG_NAME M_A_CPU0_SA_CB<7>
J 0
(-1590 2810);
DISPLAY 0.659574 (-1590 2810);
PAINT MONO (-1590 2810);
DISPLAY INVISIBLE (-1590 2810);
FORCEPROP 1 LASTPIN (-1600 2800) BN 7
J 2
(-1588 2808);
DISPLAY 0.680851 (-1588 2808);
PAINT GREEN (-1588 2808);
FORCEPROP 2 LAST CDS_LIB standard
J 0
(-1650 2800);
DISPLAY INVISIBLE (-1650 2800);
FORCEPROP 1 LAST BODY_TYPE PLUMBING
J 2
(-1650 2850);
DISPLAY 0.872340 (-1650 2850);
PAINT GREEN (-1650 2850);
DISPLAY INVISIBLE (-1650 2850);
FORCEPROP 1 LAST HDL_TAP TRUE
J 2
(-1975 2675);
DISPLAY 0.872340 (-1975 2675);
DISPLAY INVISIBLE (-1975 2675);
FORCEPROP 1 LAST PATH I38
J 2
(-1648 2800);
DISPLAY 0.872340 (-1648 2800);
PAINT GREEN (-1648 2800);
DISPLAY INVISIBLE (-1648 2800);
FORCEADD TAP..1
R 2
(-1650 2750);
FORCEPROP 3 LASTPIN (-1600 2750) SIG_NAME M_A_CPU0_SA_CB<6>
J 0
(-1590 2760);
DISPLAY 0.659574 (-1590 2760);
PAINT MONO (-1590 2760);
DISPLAY INVISIBLE (-1590 2760);
FORCEPROP 1 LASTPIN (-1600 2750) BN 6
J 2
(-1588 2758);
DISPLAY 0.680851 (-1588 2758);
PAINT GREEN (-1588 2758);
FORCEPROP 2 LAST CDS_LIB standard
J 0
(-1650 2750);
DISPLAY INVISIBLE (-1650 2750);
FORCEPROP 1 LAST BODY_TYPE PLUMBING
J 2
(-1650 2800);
DISPLAY 0.872340 (-1650 2800);
PAINT GREEN (-1650 2800);
DISPLAY INVISIBLE (-1650 2800);
FORCEPROP 1 LAST HDL_TAP TRUE
J 2
(-1975 2625);
DISPLAY 0.872340 (-1975 2625);
DISPLAY INVISIBLE (-1975 2625);
FORCEPROP 1 LAST PATH I39
J 2
(-1648 2750);
DISPLAY 0.872340 (-1648 2750);
PAINT GREEN (-1648 2750);
DISPLAY INVISIBLE (-1648 2750);
FORCEADD OFFPAGE..2
R 2
(-2575 750);
FORCEPROP 2 LAST $XR0 20 
J 0
(-2799 750);
DISPLAY 0.638298 (-2799 750);
PAINT MONO (-2799 750);
FORCEPROP 2 LAST CDS_LIB standard
J 0
(-2575 750);
PAINT MONO (-2575 750);
DISPLAY INVISIBLE (-2575 750);
FORCEPROP 1 LAST OFFPAGE TRUE
J 2
(-2900 625);
DISPLAY 0.872340 (-2900 625);
DISPLAY INVISIBLE (-2900 625);
FORCEPROP 1 LAST COMMENT_BODY TRUE
J 2
(-2530 655);
DISPLAY 0.872340 (-2530 655);
PAINT GREEN (-2530 655);
DISPLAY INVISIBLE (-2530 655);
FORCEPROP 2 LAST PATH I4
J 0
(-2525 825);
DISPLAY 1.021277 (-2525 825);
DISPLAY INVISIBLE (-2525 825);
FORCEADD TAP..1
R 2
(-1650 3550);
FORCEPROP 3 LASTPIN (-1600 3550) SIG_NAME M_A_CPU0_SB_CA<1>
J 0
(-1590 3560);
DISPLAY 0.659574 (-1590 3560);
PAINT MONO (-1590 3560);
DISPLAY INVISIBLE (-1590 3560);
FORCEPROP 1 LASTPIN (-1600 3550) BN 1
J 2
(-1588 3558);
DISPLAY 0.680851 (-1588 3558);
PAINT GREEN (-1588 3558);
FORCEPROP 2 LAST CDS_LIB standard
J 0
(-1650 3550);
DISPLAY INVISIBLE (-1650 3550);
FORCEPROP 1 LAST BODY_TYPE PLUMBING
J 2
(-1650 3600);
DISPLAY 0.872340 (-1650 3600);
PAINT GREEN (-1650 3600);
DISPLAY INVISIBLE (-1650 3600);
FORCEPROP 1 LAST HDL_TAP TRUE
J 2
(-1975 3425);
DISPLAY 0.872340 (-1975 3425);
DISPLAY INVISIBLE (-1975 3425);
FORCEPROP 1 LAST PATH I40
J 2
(-1648 3550);
DISPLAY 0.872340 (-1648 3550);
PAINT GREEN (-1648 3550);
DISPLAY INVISIBLE (-1648 3550);
FORCEADD TAP..1
R 2
(-1650 3600);
FORCEPROP 3 LASTPIN (-1600 3600) SIG_NAME M_A_CPU0_SB_CA<2>
J 0
(-1590 3610);
DISPLAY 0.659574 (-1590 3610);
PAINT MONO (-1590 3610);
DISPLAY INVISIBLE (-1590 3610);
FORCEPROP 1 LASTPIN (-1600 3600) BN 2
J 2
(-1588 3608);
DISPLAY 0.680851 (-1588 3608);
PAINT GREEN (-1588 3608);
FORCEPROP 2 LAST CDS_LIB standard
J 0
(-1650 3600);
DISPLAY INVISIBLE (-1650 3600);
FORCEPROP 1 LAST BODY_TYPE PLUMBING
J 2
(-1650 3650);
DISPLAY 0.872340 (-1650 3650);
PAINT GREEN (-1650 3650);
DISPLAY INVISIBLE (-1650 3650);
FORCEPROP 1 LAST HDL_TAP TRUE
J 2
(-1975 3475);
DISPLAY 0.872340 (-1975 3475);
DISPLAY INVISIBLE (-1975 3475);
FORCEPROP 1 LAST PATH I41
J 2
(-1648 3600);
DISPLAY 0.872340 (-1648 3600);
PAINT GREEN (-1648 3600);
DISPLAY INVISIBLE (-1648 3600);
FORCEADD TAP..1
R 2
(-1650 3500);
FORCEPROP 3 LASTPIN (-1600 3500) SIG_NAME M_A_CPU0_SB_CA<0>
J 0
(-1590 3510);
DISPLAY 0.659574 (-1590 3510);
PAINT MONO (-1590 3510);
DISPLAY INVISIBLE (-1590 3510);
FORCEPROP 1 LASTPIN (-1600 3500) BN 0
J 2
(-1588 3508);
DISPLAY 0.680851 (-1588 3508);
PAINT GREEN (-1588 3508);
FORCEPROP 2 LAST CDS_LIB standard
J 0
(-1650 3500);
DISPLAY INVISIBLE (-1650 3500);
FORCEPROP 1 LAST BODY_TYPE PLUMBING
J 2
(-1650 3550);
DISPLAY 0.872340 (-1650 3550);
PAINT GREEN (-1650 3550);
DISPLAY INVISIBLE (-1650 3550);
FORCEPROP 1 LAST HDL_TAP TRUE
J 2
(-1975 3375);
DISPLAY 0.872340 (-1975 3375);
DISPLAY INVISIBLE (-1975 3375);
FORCEPROP 1 LAST PATH I42
J 2
(-1648 3500);
DISPLAY 0.872340 (-1648 3500);
PAINT GREEN (-1648 3500);
DISPLAY INVISIBLE (-1648 3500);
FORCEADD TAP..1
R 2
(-1650 3650);
FORCEPROP 3 LASTPIN (-1600 3650) SIG_NAME M_A_CPU0_SB_CA<3>
J 0
(-1590 3660);
DISPLAY 0.659574 (-1590 3660);
PAINT MONO (-1590 3660);
DISPLAY INVISIBLE (-1590 3660);
FORCEPROP 1 LASTPIN (-1600 3650) BN 3
J 2
(-1588 3658);
DISPLAY 0.680851 (-1588 3658);
PAINT GREEN (-1588 3658);
FORCEPROP 2 LAST CDS_LIB standard
J 0
(-1650 3650);
DISPLAY INVISIBLE (-1650 3650);
FORCEPROP 1 LAST BODY_TYPE PLUMBING
J 2
(-1650 3700);
DISPLAY 0.872340 (-1650 3700);
PAINT GREEN (-1650 3700);
DISPLAY INVISIBLE (-1650 3700);
FORCEPROP 1 LAST HDL_TAP TRUE
J 2
(-1975 3525);
DISPLAY 0.872340 (-1975 3525);
DISPLAY INVISIBLE (-1975 3525);
FORCEPROP 1 LAST PATH I43
J 2
(-1648 3650);
DISPLAY 0.872340 (-1648 3650);
PAINT GREEN (-1648 3650);
DISPLAY INVISIBLE (-1648 3650);
FORCEADD TAP..1
R 2
(-1650 3700);
FORCEPROP 3 LASTPIN (-1600 3700) SIG_NAME M_A_CPU0_SB_CA<4>
J 0
(-1590 3710);
DISPLAY 0.659574 (-1590 3710);
PAINT MONO (-1590 3710);
DISPLAY INVISIBLE (-1590 3710);
FORCEPROP 1 LASTPIN (-1600 3700) BN 4
J 2
(-1588 3708);
DISPLAY 0.680851 (-1588 3708);
PAINT GREEN (-1588 3708);
FORCEPROP 2 LAST CDS_LIB standard
J 0
(-1650 3700);
DISPLAY INVISIBLE (-1650 3700);
FORCEPROP 1 LAST BODY_TYPE PLUMBING
J 2
(-1650 3750);
DISPLAY 0.872340 (-1650 3750);
PAINT GREEN (-1650 3750);
DISPLAY INVISIBLE (-1650 3750);
FORCEPROP 1 LAST HDL_TAP TRUE
J 2
(-1975 3575);
DISPLAY 0.872340 (-1975 3575);
DISPLAY INVISIBLE (-1975 3575);
FORCEPROP 1 LAST PATH I44
J 2
(-1648 3700);
DISPLAY 0.872340 (-1648 3700);
PAINT GREEN (-1648 3700);
DISPLAY INVISIBLE (-1648 3700);
FORCEADD TAP..1
R 2
(-1650 3750);
FORCEPROP 3 LASTPIN (-1600 3750) SIG_NAME M_A_CPU0_SB_CA<5>
J 0
(-1590 3760);
DISPLAY 0.659574 (-1590 3760);
PAINT MONO (-1590 3760);
DISPLAY INVISIBLE (-1590 3760);
FORCEPROP 1 LASTPIN (-1600 3750) BN 5
J 2
(-1588 3758);
DISPLAY 0.680851 (-1588 3758);
PAINT GREEN (-1588 3758);
FORCEPROP 2 LAST CDS_LIB standard
J 0
(-1650 3750);
DISPLAY INVISIBLE (-1650 3750);
FORCEPROP 1 LAST BODY_TYPE PLUMBING
J 2
(-1650 3800);
DISPLAY 0.872340 (-1650 3800);
PAINT GREEN (-1650 3800);
DISPLAY INVISIBLE (-1650 3800);
FORCEPROP 1 LAST HDL_TAP TRUE
J 2
(-1975 3625);
DISPLAY 0.872340 (-1975 3625);
DISPLAY INVISIBLE (-1975 3625);
FORCEPROP 1 LAST PATH I45
J 2
(-1648 3750);
DISPLAY 0.872340 (-1648 3750);
PAINT GREEN (-1648 3750);
DISPLAY INVISIBLE (-1648 3750);
FORCEADD TAP..1
R 2
(-1650 3800);
FORCEPROP 3 LASTPIN (-1600 3800) SIG_NAME M_A_CPU0_SB_CA<6>
J 0
(-1590 3810);
DISPLAY 0.659574 (-1590 3810);
PAINT MONO (-1590 3810);
DISPLAY INVISIBLE (-1590 3810);
FORCEPROP 1 LASTPIN (-1600 3800) BN 6
J 2
(-1588 3808);
DISPLAY 0.680851 (-1588 3808);
PAINT GREEN (-1588 3808);
FORCEPROP 2 LAST CDS_LIB standard
J 0
(-1650 3800);
DISPLAY INVISIBLE (-1650 3800);
FORCEPROP 1 LAST BODY_TYPE PLUMBING
J 2
(-1650 3850);
DISPLAY 0.872340 (-1650 3850);
PAINT GREEN (-1650 3850);
DISPLAY INVISIBLE (-1650 3850);
FORCEPROP 1 LAST HDL_TAP TRUE
J 2
(-1975 3675);
DISPLAY 0.872340 (-1975 3675);
DISPLAY INVISIBLE (-1975 3675);
FORCEPROP 1 LAST PATH I46
J 2
(-1648 3800);
DISPLAY 0.872340 (-1648 3800);
PAINT GREEN (-1648 3800);
DISPLAY INVISIBLE (-1648 3800);
FORCEADD TAP..1
R 2
(-1650 3900);
FORCEPROP 3 LASTPIN (-1600 3900) SIG_NAME M_A_CPU0_SA_CA<0>
J 0
(-1590 3910);
DISPLAY 0.659574 (-1590 3910);
PAINT MONO (-1590 3910);
DISPLAY INVISIBLE (-1590 3910);
FORCEPROP 1 LASTPIN (-1600 3900) BN 0
J 2
(-1588 3908);
DISPLAY 0.680851 (-1588 3908);
PAINT GREEN (-1588 3908);
FORCEPROP 2 LAST CDS_LIB standard
J 0
(-1650 3900);
DISPLAY INVISIBLE (-1650 3900);
FORCEPROP 1 LAST BODY_TYPE PLUMBING
J 2
(-1650 3950);
DISPLAY 0.872340 (-1650 3950);
PAINT GREEN (-1650 3950);
DISPLAY INVISIBLE (-1650 3950);
FORCEPROP 1 LAST HDL_TAP TRUE
J 2
(-1975 3775);
DISPLAY 0.872340 (-1975 3775);
DISPLAY INVISIBLE (-1975 3775);
FORCEPROP 1 LAST PATH I47
J 2
(-1648 3900);
DISPLAY 0.872340 (-1648 3900);
PAINT GREEN (-1648 3900);
DISPLAY INVISIBLE (-1648 3900);
FORCEADD TAP..1
R 2
(-1650 3950);
FORCEPROP 3 LASTPIN (-1600 3950) SIG_NAME M_A_CPU0_SA_CA<1>
J 0
(-1590 3960);
DISPLAY 0.659574 (-1590 3960);
PAINT MONO (-1590 3960);
DISPLAY INVISIBLE (-1590 3960);
FORCEPROP 1 LASTPIN (-1600 3950) BN 1
J 2
(-1588 3958);
DISPLAY 0.680851 (-1588 3958);
PAINT GREEN (-1588 3958);
FORCEPROP 2 LAST CDS_LIB standard
J 0
(-1650 3950);
DISPLAY INVISIBLE (-1650 3950);
FORCEPROP 1 LAST BODY_TYPE PLUMBING
J 2
(-1650 4000);
DISPLAY 0.872340 (-1650 4000);
PAINT GREEN (-1650 4000);
DISPLAY INVISIBLE (-1650 4000);
FORCEPROP 1 LAST HDL_TAP TRUE
J 2
(-1975 3825);
DISPLAY 0.872340 (-1975 3825);
DISPLAY INVISIBLE (-1975 3825);
FORCEPROP 1 LAST PATH I48
J 2
(-1648 3950);
DISPLAY 0.872340 (-1648 3950);
PAINT GREEN (-1648 3950);
DISPLAY INVISIBLE (-1648 3950);
FORCEADD TAP..1
(0 1000);
FORCEPROP 3 LASTPIN (-50 1000) SIG_NAME M_A_CPU0_SB_DQ<0>
J 0
(-40 1010);
DISPLAY 0.659574 (-40 1010);
PAINT MONO (-40 1010);
DISPLAY INVISIBLE (-40 1010);
FORCEPROP 1 LASTPIN (-50 1000) BN 0
J 0
(-62 1008);
DISPLAY 0.680851 (-62 1008);
PAINT GREEN (-62 1008);
FORCEPROP 2 LAST CDS_LIB standard
J 0
(0 1000);
PAINT MONO (0 1000);
DISPLAY INVISIBLE (0 1000);
FORCEPROP 1 LAST BODY_TYPE PLUMBING
J 0
(0 1050);
DISPLAY 0.872340 (0 1050);
PAINT GREEN (0 1050);
DISPLAY INVISIBLE (0 1050);
FORCEPROP 1 LAST HDL_TAP TRUE
J 0
(325 875);
DISPLAY 0.872340 (325 875);
DISPLAY INVISIBLE (325 875);
FORCEPROP 1 LAST PATH I49
J 0
(-2 1000);
DISPLAY 0.872340 (-2 1000);
PAINT GREEN (-2 1000);
DISPLAY INVISIBLE (-2 1000);
FORCEADD TAP..1
(0 1050);
FORCEPROP 3 LASTPIN (-50 1050) SIG_NAME M_A_CPU0_SB_DQ<1>
J 0
(-40 1060);
DISPLAY 0.659574 (-40 1060);
PAINT MONO (-40 1060);
DISPLAY INVISIBLE (-40 1060);
FORCEPROP 1 LASTPIN (-50 1050) BN 1
J 0
(-62 1058);
DISPLAY 0.680851 (-62 1058);
PAINT GREEN (-62 1058);
FORCEPROP 2 LAST CDS_LIB standard
J 0
(0 1050);
PAINT MONO (0 1050);
DISPLAY INVISIBLE (0 1050);
FORCEPROP 1 LAST BODY_TYPE PLUMBING
J 0
(0 1100);
DISPLAY 0.872340 (0 1100);
PAINT GREEN (0 1100);
DISPLAY INVISIBLE (0 1100);
FORCEPROP 1 LAST HDL_TAP TRUE
J 0
(325 925);
DISPLAY 0.872340 (325 925);
DISPLAY INVISIBLE (325 925);
FORCEPROP 1 LAST PATH I50
J 0
(-2 1050);
DISPLAY 0.872340 (-2 1050);
PAINT GREEN (-2 1050);
DISPLAY INVISIBLE (-2 1050);
FORCEADD TAP..1
(0 1100);
FORCEPROP 3 LASTPIN (-50 1100) SIG_NAME M_A_CPU0_SB_DQ<2>
J 0
(-40 1110);
DISPLAY 0.659574 (-40 1110);
PAINT MONO (-40 1110);
DISPLAY INVISIBLE (-40 1110);
FORCEPROP 1 LASTPIN (-50 1100) BN 2
J 0
(-62 1108);
DISPLAY 0.680851 (-62 1108);
PAINT GREEN (-62 1108);
FORCEPROP 2 LAST CDS_LIB standard
J 0
(0 1100);
PAINT MONO (0 1100);
DISPLAY INVISIBLE (0 1100);
FORCEPROP 1 LAST BODY_TYPE PLUMBING
J 0
(0 1150);
DISPLAY 0.872340 (0 1150);
PAINT GREEN (0 1150);
DISPLAY INVISIBLE (0 1150);
FORCEPROP 1 LAST HDL_TAP TRUE
J 0
(325 975);
DISPLAY 0.872340 (325 975);
DISPLAY INVISIBLE (325 975);
FORCEPROP 1 LAST PATH I51
J 0
(-2 1100);
DISPLAY 0.872340 (-2 1100);
PAINT GREEN (-2 1100);
DISPLAY INVISIBLE (-2 1100);
FORCEADD TAP..1
(0 1150);
FORCEPROP 3 LASTPIN (-50 1150) SIG_NAME M_A_CPU0_SB_DQ<3>
J 0
(-40 1160);
DISPLAY 0.659574 (-40 1160);
PAINT MONO (-40 1160);
DISPLAY INVISIBLE (-40 1160);
FORCEPROP 1 LASTPIN (-50 1150) BN 3
J 0
(-62 1158);
DISPLAY 0.680851 (-62 1158);
PAINT GREEN (-62 1158);
FORCEPROP 2 LAST CDS_LIB standard
J 0
(0 1150);
PAINT MONO (0 1150);
DISPLAY INVISIBLE (0 1150);
FORCEPROP 1 LAST BODY_TYPE PLUMBING
J 0
(0 1200);
DISPLAY 0.872340 (0 1200);
PAINT GREEN (0 1200);
DISPLAY INVISIBLE (0 1200);
FORCEPROP 1 LAST HDL_TAP TRUE
J 0
(325 1025);
DISPLAY 0.872340 (325 1025);
DISPLAY INVISIBLE (325 1025);
FORCEPROP 1 LAST PATH I52
J 0
(-2 1150);
DISPLAY 0.872340 (-2 1150);
PAINT GREEN (-2 1150);
DISPLAY INVISIBLE (-2 1150);
FORCEADD TAP..1
(0 1200);
FORCEPROP 3 LASTPIN (-50 1200) SIG_NAME M_A_CPU0_SB_DQ<4>
J 0
(-40 1210);
DISPLAY 0.659574 (-40 1210);
PAINT MONO (-40 1210);
DISPLAY INVISIBLE (-40 1210);
FORCEPROP 1 LASTPIN (-50 1200) BN 4
J 0
(-62 1208);
DISPLAY 0.680851 (-62 1208);
PAINT GREEN (-62 1208);
FORCEPROP 2 LAST CDS_LIB standard
J 0
(0 1200);
PAINT MONO (0 1200);
DISPLAY INVISIBLE (0 1200);
FORCEPROP 1 LAST BODY_TYPE PLUMBING
J 0
(0 1250);
DISPLAY 0.872340 (0 1250);
PAINT GREEN (0 1250);
DISPLAY INVISIBLE (0 1250);
FORCEPROP 1 LAST HDL_TAP TRUE
J 0
(325 1075);
DISPLAY 0.872340 (325 1075);
DISPLAY INVISIBLE (325 1075);
FORCEPROP 1 LAST PATH I53
J 0
(-2 1200);
DISPLAY 0.872340 (-2 1200);
PAINT GREEN (-2 1200);
DISPLAY INVISIBLE (-2 1200);
FORCEADD TAP..1
(0 1250);
FORCEPROP 3 LASTPIN (-50 1250) SIG_NAME M_A_CPU0_SB_DQ<5>
J 0
(-40 1260);
DISPLAY 0.659574 (-40 1260);
PAINT MONO (-40 1260);
DISPLAY INVISIBLE (-40 1260);
FORCEPROP 1 LASTPIN (-50 1250) BN 5
J 0
(-62 1258);
DISPLAY 0.680851 (-62 1258);
PAINT GREEN (-62 1258);
FORCEPROP 2 LAST CDS_LIB standard
J 0
(0 1250);
PAINT MONO (0 1250);
DISPLAY INVISIBLE (0 1250);
FORCEPROP 1 LAST BODY_TYPE PLUMBING
J 0
(0 1300);
DISPLAY 0.872340 (0 1300);
PAINT GREEN (0 1300);
DISPLAY INVISIBLE (0 1300);
FORCEPROP 1 LAST HDL_TAP TRUE
J 0
(325 1125);
DISPLAY 0.872340 (325 1125);
DISPLAY INVISIBLE (325 1125);
FORCEPROP 1 LAST PATH I54
J 0
(-2 1250);
DISPLAY 0.872340 (-2 1250);
PAINT GREEN (-2 1250);
DISPLAY INVISIBLE (-2 1250);
FORCEADD TAP..1
(0 1300);
FORCEPROP 3 LASTPIN (-50 1300) SIG_NAME M_A_CPU0_SB_DQ<6>
J 0
(-40 1310);
DISPLAY 0.659574 (-40 1310);
PAINT MONO (-40 1310);
DISPLAY INVISIBLE (-40 1310);
FORCEPROP 1 LASTPIN (-50 1300) BN 6
J 0
(-62 1308);
DISPLAY 0.680851 (-62 1308);
PAINT GREEN (-62 1308);
FORCEPROP 2 LAST CDS_LIB standard
J 0
(0 1300);
PAINT MONO (0 1300);
DISPLAY INVISIBLE (0 1300);
FORCEPROP 1 LAST BODY_TYPE PLUMBING
J 0
(0 1350);
DISPLAY 0.872340 (0 1350);
PAINT GREEN (0 1350);
DISPLAY INVISIBLE (0 1350);
FORCEPROP 1 LAST HDL_TAP TRUE
J 0
(325 1175);
DISPLAY 0.872340 (325 1175);
DISPLAY INVISIBLE (325 1175);
FORCEPROP 1 LAST PATH I55
J 0
(-2 1300);
DISPLAY 0.872340 (-2 1300);
PAINT GREEN (-2 1300);
DISPLAY INVISIBLE (-2 1300);
FORCEADD TAP..1
(0 1400);
FORCEPROP 3 LASTPIN (-50 1400) SIG_NAME M_A_CPU0_SB_DQ<8>
J 0
(-40 1410);
DISPLAY 0.659574 (-40 1410);
PAINT MONO (-40 1410);
DISPLAY INVISIBLE (-40 1410);
FORCEPROP 1 LASTPIN (-50 1400) BN 8
J 0
(-62 1408);
DISPLAY 0.680851 (-62 1408);
PAINT GREEN (-62 1408);
FORCEPROP 2 LAST CDS_LIB standard
J 0
(0 1400);
PAINT MONO (0 1400);
DISPLAY INVISIBLE (0 1400);
FORCEPROP 1 LAST BODY_TYPE PLUMBING
J 0
(0 1450);
DISPLAY 0.872340 (0 1450);
PAINT GREEN (0 1450);
DISPLAY INVISIBLE (0 1450);
FORCEPROP 1 LAST HDL_TAP TRUE
J 0
(325 1275);
DISPLAY 0.872340 (325 1275);
DISPLAY INVISIBLE (325 1275);
FORCEPROP 1 LAST PATH I56
J 0
(-2 1400);
DISPLAY 0.872340 (-2 1400);
PAINT GREEN (-2 1400);
DISPLAY INVISIBLE (-2 1400);
FORCEADD TAP..1
(0 1350);
FORCEPROP 3 LASTPIN (-50 1350) SIG_NAME M_A_CPU0_SB_DQ<7>
J 0
(-40 1360);
DISPLAY 0.659574 (-40 1360);
PAINT MONO (-40 1360);
DISPLAY INVISIBLE (-40 1360);
FORCEPROP 1 LASTPIN (-50 1350) BN 7
J 0
(-62 1358);
DISPLAY 0.680851 (-62 1358);
PAINT GREEN (-62 1358);
FORCEPROP 2 LAST CDS_LIB standard
J 0
(0 1350);
PAINT MONO (0 1350);
DISPLAY INVISIBLE (0 1350);
FORCEPROP 1 LAST BODY_TYPE PLUMBING
J 0
(0 1400);
DISPLAY 0.872340 (0 1400);
PAINT GREEN (0 1400);
DISPLAY INVISIBLE (0 1400);
FORCEPROP 1 LAST HDL_TAP TRUE
J 0
(325 1225);
DISPLAY 0.872340 (325 1225);
DISPLAY INVISIBLE (325 1225);
FORCEPROP 1 LAST PATH I57
J 0
(-2 1350);
DISPLAY 0.872340 (-2 1350);
PAINT GREEN (-2 1350);
DISPLAY INVISIBLE (-2 1350);
FORCEADD TAP..1
(0 1450);
FORCEPROP 3 LASTPIN (-50 1450) SIG_NAME M_A_CPU0_SB_DQ<9>
J 0
(-40 1460);
DISPLAY 0.659574 (-40 1460);
PAINT MONO (-40 1460);
DISPLAY INVISIBLE (-40 1460);
FORCEPROP 1 LASTPIN (-50 1450) BN 9
J 0
(-62 1458);
DISPLAY 0.680851 (-62 1458);
PAINT GREEN (-62 1458);
FORCEPROP 2 LAST CDS_LIB standard
J 0
(0 1450);
PAINT MONO (0 1450);
DISPLAY INVISIBLE (0 1450);
FORCEPROP 1 LAST BODY_TYPE PLUMBING
J 0
(0 1500);
DISPLAY 0.872340 (0 1500);
PAINT GREEN (0 1500);
DISPLAY INVISIBLE (0 1500);
FORCEPROP 1 LAST HDL_TAP TRUE
J 0
(325 1325);
DISPLAY 0.872340 (325 1325);
DISPLAY INVISIBLE (325 1325);
FORCEPROP 1 LAST PATH I58
J 0
(-2 1450);
DISPLAY 0.872340 (-2 1450);
PAINT GREEN (-2 1450);
DISPLAY INVISIBLE (-2 1450);
FORCEADD TAP..1
(0 1500);
FORCEPROP 3 LASTPIN (-50 1500) SIG_NAME M_A_CPU0_SB_DQ<10>
J 0
(-40 1510);
DISPLAY 0.659574 (-40 1510);
PAINT MONO (-40 1510);
DISPLAY INVISIBLE (-40 1510);
FORCEPROP 1 LASTPIN (-50 1500) BN 10
J 0
(-62 1508);
DISPLAY 0.680851 (-62 1508);
PAINT GREEN (-62 1508);
FORCEPROP 2 LAST CDS_LIB standard
J 0
(0 1500);
PAINT MONO (0 1500);
DISPLAY INVISIBLE (0 1500);
FORCEPROP 1 LAST BODY_TYPE PLUMBING
J 0
(0 1550);
DISPLAY 0.872340 (0 1550);
PAINT GREEN (0 1550);
DISPLAY INVISIBLE (0 1550);
FORCEPROP 1 LAST HDL_TAP TRUE
J 0
(325 1375);
DISPLAY 0.872340 (325 1375);
DISPLAY INVISIBLE (325 1375);
FORCEPROP 1 LAST PATH I59
J 0
(-2 1500);
DISPLAY 0.872340 (-2 1500);
PAINT GREEN (-2 1500);
DISPLAY INVISIBLE (-2 1500);
FORCEADD OFFPAGE..1
(-2475 1650);
FORCEPROP 2 LAST $XR7 89 
J 0
(-2847 1614);
DISPLAY 0.638298 (-2847 1614);
PAINT MONO (-2847 1614);
FORCEPROP 2 LAST $XR6 88 
J 0
(-2757 1614);
DISPLAY 0.638298 (-2757 1614);
PAINT MONO (-2757 1614);
FORCEPROP 2 LAST $XR5 87 
J 0
(-3207 1650);
DISPLAY 0.638298 (-3207 1650);
PAINT MONO (-3207 1650);
FORCEPROP 2 LAST $XR4 86 
J 0
(-3117 1650);
DISPLAY 0.638298 (-3117 1650);
PAINT MONO (-3117 1650);
FORCEPROP 2 LAST $XR3 85 
J 0
(-3027 1650);
DISPLAY 0.638298 (-3027 1650);
PAINT MONO (-3027 1650);
FORCEPROP 2 LAST $XR2 84 
J 0
(-2937 1650);
DISPLAY 0.638298 (-2937 1650);
PAINT MONO (-2937 1650);
FORCEPROP 2 LAST $XR1 82 
J 0
(-2847 1650);
DISPLAY 0.638298 (-2847 1650);
PAINT MONO (-2847 1650);
FORCEPROP 2 LAST $XR0 229 
J 0
(-2757 1650);
DISPLAY 0.638298 (-2757 1650);
PAINT MONO (-2757 1650);
FORCEPROP 2 LAST CDS_LIB standard
J 0
(-2475 1650);
PAINT MONO (-2475 1650);
DISPLAY INVISIBLE (-2475 1650);
FORCEPROP 1 LAST OFFPAGE TRUE
J 0
(-2150 1525);
DISPLAY 0.872340 (-2150 1525);
DISPLAY INVISIBLE (-2150 1525);
FORCEPROP 1 LAST COMMENT_BODY TRUE
J 0
(-2350 1550);
DISPLAY 0.872340 (-2350 1550);
PAINT GREEN (-2350 1550);
DISPLAY INVISIBLE (-2350 1550);
FORCEPROP 2 LAST PATH I6
J 0
(-2425 1725);
DISPLAY 1.021277 (-2425 1725);
DISPLAY INVISIBLE (-2425 1725);
FORCEADD TAP..1
(0 1550);
FORCEPROP 3 LASTPIN (-50 1550) SIG_NAME M_A_CPU0_SB_DQ<11>
J 0
(-40 1560);
DISPLAY 0.659574 (-40 1560);
PAINT MONO (-40 1560);
DISPLAY INVISIBLE (-40 1560);
FORCEPROP 1 LASTPIN (-50 1550) BN 11
J 0
(-62 1558);
DISPLAY 0.680851 (-62 1558);
PAINT GREEN (-62 1558);
FORCEPROP 2 LAST CDS_LIB standard
J 0
(0 1550);
PAINT MONO (0 1550);
DISPLAY INVISIBLE (0 1550);
FORCEPROP 1 LAST BODY_TYPE PLUMBING
J 0
(0 1600);
DISPLAY 0.872340 (0 1600);
PAINT GREEN (0 1600);
DISPLAY INVISIBLE (0 1600);
FORCEPROP 1 LAST HDL_TAP TRUE
J 0
(325 1425);
DISPLAY 0.872340 (325 1425);
DISPLAY INVISIBLE (325 1425);
FORCEPROP 1 LAST PATH I60
J 0
(-2 1550);
DISPLAY 0.872340 (-2 1550);
PAINT GREEN (-2 1550);
DISPLAY INVISIBLE (-2 1550);
FORCEADD TAP..1
(0 1650);
FORCEPROP 3 LASTPIN (-50 1650) SIG_NAME M_A_CPU0_SB_DQ<13>
J 0
(-40 1660);
DISPLAY 0.659574 (-40 1660);
PAINT MONO (-40 1660);
DISPLAY INVISIBLE (-40 1660);
FORCEPROP 1 LASTPIN (-50 1650) BN 13
J 0
(-62 1658);
DISPLAY 0.680851 (-62 1658);
PAINT GREEN (-62 1658);
FORCEPROP 2 LAST CDS_LIB standard
J 0
(0 1650);
PAINT MONO (0 1650);
DISPLAY INVISIBLE (0 1650);
FORCEPROP 1 LAST BODY_TYPE PLUMBING
J 0
(0 1700);
DISPLAY 0.872340 (0 1700);
PAINT GREEN (0 1700);
DISPLAY INVISIBLE (0 1700);
FORCEPROP 1 LAST HDL_TAP TRUE
J 0
(325 1525);
DISPLAY 0.872340 (325 1525);
DISPLAY INVISIBLE (325 1525);
FORCEPROP 1 LAST PATH I61
J 0
(-2 1650);
DISPLAY 0.872340 (-2 1650);
PAINT GREEN (-2 1650);
DISPLAY INVISIBLE (-2 1650);
FORCEADD TAP..1
(0 1600);
FORCEPROP 3 LASTPIN (-50 1600) SIG_NAME M_A_CPU0_SB_DQ<12>
J 0
(-40 1610);
DISPLAY 0.659574 (-40 1610);
PAINT MONO (-40 1610);
DISPLAY INVISIBLE (-40 1610);
FORCEPROP 1 LASTPIN (-50 1600) BN 12
J 0
(-62 1608);
DISPLAY 0.680851 (-62 1608);
PAINT GREEN (-62 1608);
FORCEPROP 2 LAST CDS_LIB standard
J 0
(0 1600);
PAINT MONO (0 1600);
DISPLAY INVISIBLE (0 1600);
FORCEPROP 1 LAST BODY_TYPE PLUMBING
J 0
(0 1650);
DISPLAY 0.872340 (0 1650);
PAINT GREEN (0 1650);
DISPLAY INVISIBLE (0 1650);
FORCEPROP 1 LAST HDL_TAP TRUE
J 0
(325 1475);
DISPLAY 0.872340 (325 1475);
DISPLAY INVISIBLE (325 1475);
FORCEPROP 1 LAST PATH I62
J 0
(-2 1600);
DISPLAY 0.872340 (-2 1600);
PAINT GREEN (-2 1600);
DISPLAY INVISIBLE (-2 1600);
FORCEADD TAP..1
(0 1800);
FORCEPROP 3 LASTPIN (-50 1800) SIG_NAME M_A_CPU0_SB_DQ<16>
J 0
(-40 1810);
DISPLAY 0.659574 (-40 1810);
PAINT MONO (-40 1810);
DISPLAY INVISIBLE (-40 1810);
FORCEPROP 1 LASTPIN (-50 1800) BN 16
J 0
(-62 1808);
DISPLAY 0.680851 (-62 1808);
PAINT GREEN (-62 1808);
FORCEPROP 2 LAST CDS_LIB standard
J 0
(0 1800);
PAINT MONO (0 1800);
DISPLAY INVISIBLE (0 1800);
FORCEPROP 1 LAST BODY_TYPE PLUMBING
J 0
(0 1850);
DISPLAY 0.872340 (0 1850);
PAINT GREEN (0 1850);
DISPLAY INVISIBLE (0 1850);
FORCEPROP 1 LAST HDL_TAP TRUE
J 0
(325 1675);
DISPLAY 0.872340 (325 1675);
DISPLAY INVISIBLE (325 1675);
FORCEPROP 1 LAST PATH I63
J 0
(-2 1800);
DISPLAY 0.872340 (-2 1800);
PAINT GREEN (-2 1800);
DISPLAY INVISIBLE (-2 1800);
FORCEADD TAP..1
(0 1750);
FORCEPROP 3 LASTPIN (-50 1750) SIG_NAME M_A_CPU0_SB_DQ<15>
J 0
(-40 1760);
DISPLAY 0.659574 (-40 1760);
PAINT MONO (-40 1760);
DISPLAY INVISIBLE (-40 1760);
FORCEPROP 1 LASTPIN (-50 1750) BN 15
J 0
(-62 1758);
DISPLAY 0.680851 (-62 1758);
PAINT GREEN (-62 1758);
FORCEPROP 2 LAST CDS_LIB standard
J 0
(0 1750);
PAINT MONO (0 1750);
DISPLAY INVISIBLE (0 1750);
FORCEPROP 1 LAST BODY_TYPE PLUMBING
J 0
(0 1800);
DISPLAY 0.872340 (0 1800);
PAINT GREEN (0 1800);
DISPLAY INVISIBLE (0 1800);
FORCEPROP 1 LAST HDL_TAP TRUE
J 0
(325 1625);
DISPLAY 0.872340 (325 1625);
DISPLAY INVISIBLE (325 1625);
FORCEPROP 1 LAST PATH I64
J 0
(-2 1750);
DISPLAY 0.872340 (-2 1750);
PAINT GREEN (-2 1750);
DISPLAY INVISIBLE (-2 1750);
FORCEADD TAP..1
(0 1700);
FORCEPROP 3 LASTPIN (-50 1700) SIG_NAME M_A_CPU0_SB_DQ<14>
J 0
(-40 1710);
DISPLAY 0.659574 (-40 1710);
PAINT MONO (-40 1710);
DISPLAY INVISIBLE (-40 1710);
FORCEPROP 1 LASTPIN (-50 1700) BN 14
J 0
(-62 1708);
DISPLAY 0.680851 (-62 1708);
PAINT GREEN (-62 1708);
FORCEPROP 2 LAST CDS_LIB standard
J 0
(0 1700);
PAINT MONO (0 1700);
DISPLAY INVISIBLE (0 1700);
FORCEPROP 1 LAST BODY_TYPE PLUMBING
J 0
(0 1750);
DISPLAY 0.872340 (0 1750);
PAINT GREEN (0 1750);
DISPLAY INVISIBLE (0 1750);
FORCEPROP 1 LAST HDL_TAP TRUE
J 0
(325 1575);
DISPLAY 0.872340 (325 1575);
DISPLAY INVISIBLE (325 1575);
FORCEPROP 1 LAST PATH I65
J 0
(-2 1700);
DISPLAY 0.872340 (-2 1700);
PAINT GREEN (-2 1700);
DISPLAY INVISIBLE (-2 1700);
FORCEADD TAP..1
(0 1900);
FORCEPROP 3 LASTPIN (-50 1900) SIG_NAME M_A_CPU0_SB_DQ<18>
J 0
(-40 1910);
DISPLAY 0.659574 (-40 1910);
PAINT MONO (-40 1910);
DISPLAY INVISIBLE (-40 1910);
FORCEPROP 1 LASTPIN (-50 1900) BN 18
J 0
(-62 1908);
DISPLAY 0.680851 (-62 1908);
PAINT GREEN (-62 1908);
FORCEPROP 2 LAST CDS_LIB standard
J 0
(0 1900);
PAINT MONO (0 1900);
DISPLAY INVISIBLE (0 1900);
FORCEPROP 1 LAST BODY_TYPE PLUMBING
J 0
(0 1950);
DISPLAY 0.872340 (0 1950);
PAINT GREEN (0 1950);
DISPLAY INVISIBLE (0 1950);
FORCEPROP 1 LAST HDL_TAP TRUE
J 0
(325 1775);
DISPLAY 0.872340 (325 1775);
DISPLAY INVISIBLE (325 1775);
FORCEPROP 1 LAST PATH I66
J 0
(-2 1900);
DISPLAY 0.872340 (-2 1900);
PAINT GREEN (-2 1900);
DISPLAY INVISIBLE (-2 1900);
FORCEADD TAP..1
(0 1850);
FORCEPROP 3 LASTPIN (-50 1850) SIG_NAME M_A_CPU0_SB_DQ<17>
J 0
(-40 1860);
DISPLAY 0.659574 (-40 1860);
PAINT MONO (-40 1860);
DISPLAY INVISIBLE (-40 1860);
FORCEPROP 1 LASTPIN (-50 1850) BN 17
J 0
(-62 1858);
DISPLAY 0.680851 (-62 1858);
PAINT GREEN (-62 1858);
FORCEPROP 2 LAST CDS_LIB standard
J 0
(0 1850);
PAINT MONO (0 1850);
DISPLAY INVISIBLE (0 1850);
FORCEPROP 1 LAST BODY_TYPE PLUMBING
J 0
(0 1900);
DISPLAY 0.872340 (0 1900);
PAINT GREEN (0 1900);
DISPLAY INVISIBLE (0 1900);
FORCEPROP 1 LAST HDL_TAP TRUE
J 0
(325 1725);
DISPLAY 0.872340 (325 1725);
DISPLAY INVISIBLE (325 1725);
FORCEPROP 1 LAST PATH I67
J 0
(-2 1850);
DISPLAY 0.872340 (-2 1850);
PAINT GREEN (-2 1850);
DISPLAY INVISIBLE (-2 1850);
FORCEADD TAP..1
(0 1950);
FORCEPROP 3 LASTPIN (-50 1950) SIG_NAME M_A_CPU0_SB_DQ<19>
J 0
(-40 1960);
DISPLAY 0.659574 (-40 1960);
PAINT MONO (-40 1960);
DISPLAY INVISIBLE (-40 1960);
FORCEPROP 1 LASTPIN (-50 1950) BN 19
J 0
(-62 1958);
DISPLAY 0.680851 (-62 1958);
PAINT GREEN (-62 1958);
FORCEPROP 2 LAST CDS_LIB standard
J 0
(0 1950);
PAINT MONO (0 1950);
DISPLAY INVISIBLE (0 1950);
FORCEPROP 1 LAST BODY_TYPE PLUMBING
J 0
(0 2000);
DISPLAY 0.872340 (0 2000);
PAINT GREEN (0 2000);
DISPLAY INVISIBLE (0 2000);
FORCEPROP 1 LAST HDL_TAP TRUE
J 0
(325 1825);
DISPLAY 0.872340 (325 1825);
DISPLAY INVISIBLE (325 1825);
FORCEPROP 1 LAST PATH I68
J 0
(-2 1950);
DISPLAY 0.872340 (-2 1950);
PAINT GREEN (-2 1950);
DISPLAY INVISIBLE (-2 1950);
FORCEADD TAP..1
(0 2050);
FORCEPROP 3 LASTPIN (-50 2050) SIG_NAME M_A_CPU0_SB_DQ<21>
J 0
(-40 2060);
DISPLAY 0.659574 (-40 2060);
PAINT MONO (-40 2060);
DISPLAY INVISIBLE (-40 2060);
FORCEPROP 1 LASTPIN (-50 2050) BN 21
J 0
(-62 2058);
DISPLAY 0.680851 (-62 2058);
PAINT GREEN (-62 2058);
FORCEPROP 2 LAST CDS_LIB standard
J 0
(0 2050);
PAINT MONO (0 2050);
DISPLAY INVISIBLE (0 2050);
FORCEPROP 1 LAST BODY_TYPE PLUMBING
J 0
(0 2100);
DISPLAY 0.872340 (0 2100);
PAINT GREEN (0 2100);
DISPLAY INVISIBLE (0 2100);
FORCEPROP 1 LAST HDL_TAP TRUE
J 0
(325 1925);
DISPLAY 0.872340 (325 1925);
DISPLAY INVISIBLE (325 1925);
FORCEPROP 1 LAST PATH I69
J 0
(-2 2050);
DISPLAY 0.872340 (-2 2050);
PAINT GREEN (-2 2050);
DISPLAY INVISIBLE (-2 2050);
FORCEADD OFFPAGE..1
(-2475 1700);
FORCEPROP 2 LAST $XR0 83 
J 0
(-2726 1700);
DISPLAY 0.638298 (-2726 1700);
PAINT MONO (-2726 1700);
FORCEPROP 2 LAST CDS_LIB standard
J 0
(-2475 1700);
PAINT MONO (-2475 1700);
DISPLAY INVISIBLE (-2475 1700);
FORCEPROP 1 LAST OFFPAGE TRUE
J 0
(-2150 1575);
DISPLAY 0.872340 (-2150 1575);
DISPLAY INVISIBLE (-2150 1575);
FORCEPROP 1 LAST COMMENT_BODY TRUE
J 0
(-2350 1600);
DISPLAY 0.872340 (-2350 1600);
PAINT GREEN (-2350 1600);
DISPLAY INVISIBLE (-2350 1600);
FORCEPROP 2 LAST PATH I7
J 0
(-2425 1775);
DISPLAY 1.021277 (-2425 1775);
DISPLAY INVISIBLE (-2425 1775);
FORCEADD TAP..1
(0 2000);
FORCEPROP 3 LASTPIN (-50 2000) SIG_NAME M_A_CPU0_SB_DQ<20>
J 0
(-40 2010);
DISPLAY 0.659574 (-40 2010);
PAINT MONO (-40 2010);
DISPLAY INVISIBLE (-40 2010);
FORCEPROP 1 LASTPIN (-50 2000) BN 20
J 0
(-62 2008);
DISPLAY 0.680851 (-62 2008);
PAINT GREEN (-62 2008);
FORCEPROP 2 LAST CDS_LIB standard
J 0
(0 2000);
PAINT MONO (0 2000);
DISPLAY INVISIBLE (0 2000);
FORCEPROP 1 LAST BODY_TYPE PLUMBING
J 0
(0 2050);
DISPLAY 0.872340 (0 2050);
PAINT GREEN (0 2050);
DISPLAY INVISIBLE (0 2050);
FORCEPROP 1 LAST HDL_TAP TRUE
J 0
(325 1875);
DISPLAY 0.872340 (325 1875);
DISPLAY INVISIBLE (325 1875);
FORCEPROP 1 LAST PATH I70
J 0
(-2 2000);
DISPLAY 0.872340 (-2 2000);
PAINT GREEN (-2 2000);
DISPLAY INVISIBLE (-2 2000);
FORCEADD TAP..1
(0 2150);
FORCEPROP 3 LASTPIN (-50 2150) SIG_NAME M_A_CPU0_SB_DQ<23>
J 0
(-40 2160);
DISPLAY 0.659574 (-40 2160);
PAINT MONO (-40 2160);
DISPLAY INVISIBLE (-40 2160);
FORCEPROP 1 LASTPIN (-50 2150) BN 23
J 0
(-62 2158);
DISPLAY 0.680851 (-62 2158);
PAINT GREEN (-62 2158);
FORCEPROP 2 LAST CDS_LIB standard
J 0
(0 2150);
DISPLAY INVISIBLE (0 2150);
FORCEPROP 1 LAST BODY_TYPE PLUMBING
J 0
(0 2200);
DISPLAY 0.872340 (0 2200);
PAINT GREEN (0 2200);
DISPLAY INVISIBLE (0 2200);
FORCEPROP 1 LAST HDL_TAP TRUE
J 0
(325 2025);
DISPLAY 0.872340 (325 2025);
DISPLAY INVISIBLE (325 2025);
FORCEPROP 1 LAST PATH I71
J 0
(-2 2150);
DISPLAY 0.872340 (-2 2150);
PAINT GREEN (-2 2150);
DISPLAY INVISIBLE (-2 2150);
FORCEADD TAP..1
(0 2200);
FORCEPROP 3 LASTPIN (-50 2200) SIG_NAME M_A_CPU0_SB_DQ<24>
J 0
(-40 2210);
DISPLAY 0.659574 (-40 2210);
PAINT MONO (-40 2210);
DISPLAY INVISIBLE (-40 2210);
FORCEPROP 1 LASTPIN (-50 2200) BN 24
J 0
(-62 2208);
DISPLAY 0.680851 (-62 2208);
PAINT GREEN (-62 2208);
FORCEPROP 2 LAST CDS_LIB standard
J 0
(0 2200);
DISPLAY INVISIBLE (0 2200);
FORCEPROP 1 LAST BODY_TYPE PLUMBING
J 0
(0 2250);
DISPLAY 0.872340 (0 2250);
PAINT GREEN (0 2250);
DISPLAY INVISIBLE (0 2250);
FORCEPROP 1 LAST HDL_TAP TRUE
J 0
(325 2075);
DISPLAY 0.872340 (325 2075);
DISPLAY INVISIBLE (325 2075);
FORCEPROP 1 LAST PATH I72
J 0
(-2 2200);
DISPLAY 0.872340 (-2 2200);
PAINT GREEN (-2 2200);
DISPLAY INVISIBLE (-2 2200);
FORCEADD TAP..1
(0 2100);
FORCEPROP 3 LASTPIN (-50 2100) SIG_NAME M_A_CPU0_SB_DQ<22>
J 0
(-40 2110);
DISPLAY 0.659574 (-40 2110);
PAINT MONO (-40 2110);
DISPLAY INVISIBLE (-40 2110);
FORCEPROP 1 LASTPIN (-50 2100) BN 22
J 0
(-62 2108);
DISPLAY 0.680851 (-62 2108);
PAINT GREEN (-62 2108);
FORCEPROP 2 LAST CDS_LIB standard
J 0
(0 2100);
DISPLAY INVISIBLE (0 2100);
FORCEPROP 1 LAST BODY_TYPE PLUMBING
J 0
(0 2150);
DISPLAY 0.872340 (0 2150);
PAINT GREEN (0 2150);
DISPLAY INVISIBLE (0 2150);
FORCEPROP 1 LAST HDL_TAP TRUE
J 0
(325 1975);
DISPLAY 0.872340 (325 1975);
DISPLAY INVISIBLE (325 1975);
FORCEPROP 1 LAST PATH I73
J 0
(-2 2100);
DISPLAY 0.872340 (-2 2100);
PAINT GREEN (-2 2100);
DISPLAY INVISIBLE (-2 2100);
FORCEADD TAP..1
(0 2300);
FORCEPROP 3 LASTPIN (-50 2300) SIG_NAME M_A_CPU0_SB_DQ<26>
J 0
(-40 2310);
DISPLAY 0.659574 (-40 2310);
PAINT MONO (-40 2310);
DISPLAY INVISIBLE (-40 2310);
FORCEPROP 1 LASTPIN (-50 2300) BN 26
J 0
(-62 2308);
DISPLAY 0.680851 (-62 2308);
PAINT GREEN (-62 2308);
FORCEPROP 2 LAST CDS_LIB standard
J 0
(0 2300);
DISPLAY INVISIBLE (0 2300);
FORCEPROP 1 LAST BODY_TYPE PLUMBING
J 0
(0 2350);
DISPLAY 0.872340 (0 2350);
PAINT GREEN (0 2350);
DISPLAY INVISIBLE (0 2350);
FORCEPROP 1 LAST HDL_TAP TRUE
J 0
(325 2175);
DISPLAY 0.872340 (325 2175);
DISPLAY INVISIBLE (325 2175);
FORCEPROP 1 LAST PATH I74
J 0
(-2 2300);
DISPLAY 0.872340 (-2 2300);
PAINT GREEN (-2 2300);
DISPLAY INVISIBLE (-2 2300);
FORCEADD TAP..1
(0 2250);
FORCEPROP 3 LASTPIN (-50 2250) SIG_NAME M_A_CPU0_SB_DQ<25>
J 0
(-40 2260);
DISPLAY 0.659574 (-40 2260);
PAINT MONO (-40 2260);
DISPLAY INVISIBLE (-40 2260);
FORCEPROP 1 LASTPIN (-50 2250) BN 25
J 0
(-62 2258);
DISPLAY 0.680851 (-62 2258);
PAINT GREEN (-62 2258);
FORCEPROP 2 LAST CDS_LIB standard
J 0
(0 2250);
DISPLAY INVISIBLE (0 2250);
FORCEPROP 1 LAST BODY_TYPE PLUMBING
J 0
(0 2300);
DISPLAY 0.872340 (0 2300);
PAINT GREEN (0 2300);
DISPLAY INVISIBLE (0 2300);
FORCEPROP 1 LAST HDL_TAP TRUE
J 0
(325 2125);
DISPLAY 0.872340 (325 2125);
DISPLAY INVISIBLE (325 2125);
FORCEPROP 1 LAST PATH I75
J 0
(-2 2250);
DISPLAY 0.872340 (-2 2250);
PAINT GREEN (-2 2250);
DISPLAY INVISIBLE (-2 2250);
FORCEADD TAP..1
(0 2400);
FORCEPROP 3 LASTPIN (-50 2400) SIG_NAME M_A_CPU0_SB_DQ<28>
J 0
(-40 2410);
DISPLAY 0.659574 (-40 2410);
PAINT MONO (-40 2410);
DISPLAY INVISIBLE (-40 2410);
FORCEPROP 1 LASTPIN (-50 2400) BN 28
J 0
(-62 2408);
DISPLAY 0.680851 (-62 2408);
PAINT GREEN (-62 2408);
FORCEPROP 2 LAST CDS_LIB standard
J 0
(0 2400);
DISPLAY INVISIBLE (0 2400);
FORCEPROP 1 LAST BODY_TYPE PLUMBING
J 0
(0 2450);
DISPLAY 0.872340 (0 2450);
PAINT GREEN (0 2450);
DISPLAY INVISIBLE (0 2450);
FORCEPROP 1 LAST HDL_TAP TRUE
J 0
(325 2275);
DISPLAY 0.872340 (325 2275);
DISPLAY INVISIBLE (325 2275);
FORCEPROP 1 LAST PATH I76
J 0
(-2 2400);
DISPLAY 0.872340 (-2 2400);
PAINT GREEN (-2 2400);
DISPLAY INVISIBLE (-2 2400);
FORCEADD TAP..1
(0 2450);
FORCEPROP 3 LASTPIN (-50 2450) SIG_NAME M_A_CPU0_SB_DQ<29>
J 0
(-40 2460);
DISPLAY 0.659574 (-40 2460);
PAINT MONO (-40 2460);
DISPLAY INVISIBLE (-40 2460);
FORCEPROP 1 LASTPIN (-50 2450) BN 29
J 0
(-62 2458);
DISPLAY 0.680851 (-62 2458);
PAINT GREEN (-62 2458);
FORCEPROP 2 LAST CDS_LIB standard
J 0
(0 2450);
DISPLAY INVISIBLE (0 2450);
FORCEPROP 1 LAST BODY_TYPE PLUMBING
J 0
(0 2500);
DISPLAY 0.872340 (0 2500);
PAINT GREEN (0 2500);
DISPLAY INVISIBLE (0 2500);
FORCEPROP 1 LAST HDL_TAP TRUE
J 0
(325 2325);
DISPLAY 0.872340 (325 2325);
DISPLAY INVISIBLE (325 2325);
FORCEPROP 1 LAST PATH I77
J 0
(-2 2450);
DISPLAY 0.872340 (-2 2450);
PAINT GREEN (-2 2450);
DISPLAY INVISIBLE (-2 2450);
FORCEADD TAP..1
(0 2350);
FORCEPROP 3 LASTPIN (-50 2350) SIG_NAME M_A_CPU0_SB_DQ<27>
J 0
(-40 2360);
DISPLAY 0.659574 (-40 2360);
PAINT MONO (-40 2360);
DISPLAY INVISIBLE (-40 2360);
FORCEPROP 1 LASTPIN (-50 2350) BN 27
J 0
(-62 2358);
DISPLAY 0.680851 (-62 2358);
PAINT GREEN (-62 2358);
FORCEPROP 2 LAST CDS_LIB standard
J 0
(0 2350);
DISPLAY INVISIBLE (0 2350);
FORCEPROP 1 LAST BODY_TYPE PLUMBING
J 0
(0 2400);
DISPLAY 0.872340 (0 2400);
PAINT GREEN (0 2400);
DISPLAY INVISIBLE (0 2400);
FORCEPROP 1 LAST HDL_TAP TRUE
J 0
(325 2225);
DISPLAY 0.872340 (325 2225);
DISPLAY INVISIBLE (325 2225);
FORCEPROP 1 LAST PATH I78
J 0
(-2 2350);
DISPLAY 0.872340 (-2 2350);
PAINT GREEN (-2 2350);
DISPLAY INVISIBLE (-2 2350);
FORCEADD TAP..1
(0 2550);
FORCEPROP 3 LASTPIN (-50 2550) SIG_NAME M_A_CPU0_SB_DQ<31>
J 0
(-40 2560);
DISPLAY 0.659574 (-40 2560);
PAINT MONO (-40 2560);
DISPLAY INVISIBLE (-40 2560);
FORCEPROP 1 LASTPIN (-50 2550) BN 31
J 0
(-62 2558);
DISPLAY 0.680851 (-62 2558);
PAINT GREEN (-62 2558);
FORCEPROP 2 LAST CDS_LIB standard
J 0
(0 2550);
DISPLAY INVISIBLE (0 2550);
FORCEPROP 1 LAST BODY_TYPE PLUMBING
J 0
(0 2600);
DISPLAY 0.872340 (0 2600);
PAINT GREEN (0 2600);
DISPLAY INVISIBLE (0 2600);
FORCEPROP 1 LAST HDL_TAP TRUE
J 0
(325 2425);
DISPLAY 0.872340 (325 2425);
DISPLAY INVISIBLE (325 2425);
FORCEPROP 1 LAST PATH I79
J 0
(-2 2550);
DISPLAY 0.872340 (-2 2550);
PAINT GREEN (-2 2550);
DISPLAY INVISIBLE (-2 2550);
FORCEADD OFFPAGE..1
(-2575 1850);
FORCEPROP 2 LAST $XR1 82 
J 0
(-2916 1850);
DISPLAY 0.638298 (-2916 1850);
PAINT MONO (-2916 1850);
FORCEPROP 2 LAST $XR0 20 
J 0
(-2826 1850);
DISPLAY 0.638298 (-2826 1850);
PAINT MONO (-2826 1850);
FORCEPROP 2 LAST CDS_LIB standard
J 0
(-2575 1850);
PAINT MONO (-2575 1850);
DISPLAY INVISIBLE (-2575 1850);
FORCEPROP 1 LAST OFFPAGE TRUE
J 0
(-2250 1725);
DISPLAY 0.872340 (-2250 1725);
DISPLAY INVISIBLE (-2250 1725);
FORCEPROP 1 LAST COMMENT_BODY TRUE
J 0
(-2450 1750);
DISPLAY 0.872340 (-2450 1750);
PAINT GREEN (-2450 1750);
DISPLAY INVISIBLE (-2450 1750);
FORCEPROP 2 LAST PATH I8
J 0
(-2525 1925);
DISPLAY 1.021277 (-2525 1925);
DISPLAY INVISIBLE (-2525 1925);
FORCEADD TAP..1
(0 2500);
FORCEPROP 3 LASTPIN (-50 2500) SIG_NAME M_A_CPU0_SB_DQ<30>
J 0
(-40 2510);
DISPLAY 0.659574 (-40 2510);
PAINT MONO (-40 2510);
DISPLAY INVISIBLE (-40 2510);
FORCEPROP 1 LASTPIN (-50 2500) BN 30
J 0
(-62 2508);
DISPLAY 0.680851 (-62 2508);
PAINT GREEN (-62 2508);
FORCEPROP 2 LAST CDS_LIB standard
J 0
(0 2500);
DISPLAY INVISIBLE (0 2500);
FORCEPROP 1 LAST BODY_TYPE PLUMBING
J 0
(0 2550);
DISPLAY 0.872340 (0 2550);
PAINT GREEN (0 2550);
DISPLAY INVISIBLE (0 2550);
FORCEPROP 1 LAST HDL_TAP TRUE
J 0
(325 2375);
DISPLAY 0.872340 (325 2375);
DISPLAY INVISIBLE (325 2375);
FORCEPROP 1 LAST PATH I80
J 0
(-2 2500);
DISPLAY 0.872340 (-2 2500);
PAINT GREEN (-2 2500);
DISPLAY INVISIBLE (-2 2500);
FORCEADD TAP..1
(0 2650);
FORCEPROP 3 LASTPIN (-50 2650) SIG_NAME M_A_CPU0_SA_DQ<0>
J 0
(-40 2660);
DISPLAY 0.659574 (-40 2660);
PAINT MONO (-40 2660);
DISPLAY INVISIBLE (-40 2660);
FORCEPROP 1 LASTPIN (-50 2650) BN 0
J 0
(-62 2658);
DISPLAY 0.680851 (-62 2658);
PAINT GREEN (-62 2658);
FORCEPROP 2 LAST CDS_LIB standard
J 0
(0 2650);
PAINT MONO (0 2650);
DISPLAY INVISIBLE (0 2650);
FORCEPROP 1 LAST BODY_TYPE PLUMBING
J 0
(0 2700);
DISPLAY 0.872340 (0 2700);
PAINT GREEN (0 2700);
DISPLAY INVISIBLE (0 2700);
FORCEPROP 1 LAST HDL_TAP TRUE
J 0
(325 2525);
DISPLAY 0.872340 (325 2525);
DISPLAY INVISIBLE (325 2525);
FORCEPROP 1 LAST PATH I81
J 0
(-2 2650);
DISPLAY 0.872340 (-2 2650);
PAINT GREEN (-2 2650);
DISPLAY INVISIBLE (-2 2650);
FORCEADD TAP..1
(0 2700);
FORCEPROP 3 LASTPIN (-50 2700) SIG_NAME M_A_CPU0_SA_DQ<1>
J 0
(-40 2710);
DISPLAY 0.659574 (-40 2710);
PAINT MONO (-40 2710);
DISPLAY INVISIBLE (-40 2710);
FORCEPROP 1 LASTPIN (-50 2700) BN 1
J 0
(-62 2708);
DISPLAY 0.680851 (-62 2708);
PAINT GREEN (-62 2708);
FORCEPROP 2 LAST CDS_LIB standard
J 0
(0 2700);
PAINT MONO (0 2700);
DISPLAY INVISIBLE (0 2700);
FORCEPROP 1 LAST BODY_TYPE PLUMBING
J 0
(0 2750);
DISPLAY 0.872340 (0 2750);
PAINT GREEN (0 2750);
DISPLAY INVISIBLE (0 2750);
FORCEPROP 1 LAST HDL_TAP TRUE
J 0
(325 2575);
DISPLAY 0.872340 (325 2575);
DISPLAY INVISIBLE (325 2575);
FORCEPROP 1 LAST PATH I82
J 0
(-2 2700);
DISPLAY 0.872340 (-2 2700);
PAINT GREEN (-2 2700);
DISPLAY INVISIBLE (-2 2700);
FORCEADD TAP..1
(0 2750);
FORCEPROP 3 LASTPIN (-50 2750) SIG_NAME M_A_CPU0_SA_DQ<2>
J 0
(-40 2760);
DISPLAY 0.659574 (-40 2760);
PAINT MONO (-40 2760);
DISPLAY INVISIBLE (-40 2760);
FORCEPROP 1 LASTPIN (-50 2750) BN 2
J 0
(-62 2758);
DISPLAY 0.680851 (-62 2758);
PAINT GREEN (-62 2758);
FORCEPROP 2 LAST CDS_LIB standard
J 0
(0 2750);
PAINT MONO (0 2750);
DISPLAY INVISIBLE (0 2750);
FORCEPROP 1 LAST BODY_TYPE PLUMBING
J 0
(0 2800);
DISPLAY 0.872340 (0 2800);
PAINT GREEN (0 2800);
DISPLAY INVISIBLE (0 2800);
FORCEPROP 1 LAST HDL_TAP TRUE
J 0
(325 2625);
DISPLAY 0.872340 (325 2625);
DISPLAY INVISIBLE (325 2625);
FORCEPROP 1 LAST PATH I83
J 0
(-2 2750);
DISPLAY 0.872340 (-2 2750);
PAINT GREEN (-2 2750);
DISPLAY INVISIBLE (-2 2750);
FORCEADD TAP..1
(0 2800);
FORCEPROP 3 LASTPIN (-50 2800) SIG_NAME M_A_CPU0_SA_DQ<3>
J 0
(-40 2810);
DISPLAY 0.659574 (-40 2810);
PAINT MONO (-40 2810);
DISPLAY INVISIBLE (-40 2810);
FORCEPROP 1 LASTPIN (-50 2800) BN 3
J 0
(-62 2808);
DISPLAY 0.680851 (-62 2808);
PAINT GREEN (-62 2808);
FORCEPROP 2 LAST CDS_LIB standard
J 0
(0 2800);
PAINT MONO (0 2800);
DISPLAY INVISIBLE (0 2800);
FORCEPROP 1 LAST BODY_TYPE PLUMBING
J 0
(0 2850);
DISPLAY 0.872340 (0 2850);
PAINT GREEN (0 2850);
DISPLAY INVISIBLE (0 2850);
FORCEPROP 1 LAST HDL_TAP TRUE
J 0
(325 2675);
DISPLAY 0.872340 (325 2675);
DISPLAY INVISIBLE (325 2675);
FORCEPROP 1 LAST PATH I84
J 0
(-2 2800);
DISPLAY 0.872340 (-2 2800);
PAINT GREEN (-2 2800);
DISPLAY INVISIBLE (-2 2800);
FORCEADD TAP..1
(0 2950);
FORCEPROP 3 LASTPIN (-50 2950) SIG_NAME M_A_CPU0_SA_DQ<6>
J 0
(-40 2960);
DISPLAY 0.659574 (-40 2960);
PAINT MONO (-40 2960);
DISPLAY INVISIBLE (-40 2960);
FORCEPROP 1 LASTPIN (-50 2950) BN 6
J 0
(-62 2958);
DISPLAY 0.680851 (-62 2958);
PAINT GREEN (-62 2958);
FORCEPROP 2 LAST CDS_LIB standard
J 0
(0 2950);
PAINT MONO (0 2950);
DISPLAY INVISIBLE (0 2950);
FORCEPROP 1 LAST BODY_TYPE PLUMBING
J 0
(0 3000);
DISPLAY 0.872340 (0 3000);
PAINT GREEN (0 3000);
DISPLAY INVISIBLE (0 3000);
FORCEPROP 1 LAST HDL_TAP TRUE
J 0
(325 2825);
DISPLAY 0.872340 (325 2825);
DISPLAY INVISIBLE (325 2825);
FORCEPROP 1 LAST PATH I85
J 0
(-2 2950);
DISPLAY 0.872340 (-2 2950);
PAINT GREEN (-2 2950);
DISPLAY INVISIBLE (-2 2950);
FORCEADD TAP..1
(0 2900);
FORCEPROP 3 LASTPIN (-50 2900) SIG_NAME M_A_CPU0_SA_DQ<5>
J 0
(-40 2910);
DISPLAY 0.659574 (-40 2910);
PAINT MONO (-40 2910);
DISPLAY INVISIBLE (-40 2910);
FORCEPROP 1 LASTPIN (-50 2900) BN 5
J 0
(-62 2908);
DISPLAY 0.680851 (-62 2908);
PAINT GREEN (-62 2908);
FORCEPROP 2 LAST CDS_LIB standard
J 0
(0 2900);
PAINT MONO (0 2900);
DISPLAY INVISIBLE (0 2900);
FORCEPROP 1 LAST BODY_TYPE PLUMBING
J 0
(0 2950);
DISPLAY 0.872340 (0 2950);
PAINT GREEN (0 2950);
DISPLAY INVISIBLE (0 2950);
FORCEPROP 1 LAST HDL_TAP TRUE
J 0
(325 2775);
DISPLAY 0.872340 (325 2775);
DISPLAY INVISIBLE (325 2775);
FORCEPROP 1 LAST PATH I86
J 0
(-2 2900);
DISPLAY 0.872340 (-2 2900);
PAINT GREEN (-2 2900);
DISPLAY INVISIBLE (-2 2900);
FORCEADD TAP..1
(0 2850);
FORCEPROP 3 LASTPIN (-50 2850) SIG_NAME M_A_CPU0_SA_DQ<4>
J 0
(-40 2860);
DISPLAY 0.659574 (-40 2860);
PAINT MONO (-40 2860);
DISPLAY INVISIBLE (-40 2860);
FORCEPROP 1 LASTPIN (-50 2850) BN 4
J 0
(-62 2858);
DISPLAY 0.680851 (-62 2858);
PAINT GREEN (-62 2858);
FORCEPROP 2 LAST CDS_LIB standard
J 0
(0 2850);
PAINT MONO (0 2850);
DISPLAY INVISIBLE (0 2850);
FORCEPROP 1 LAST BODY_TYPE PLUMBING
J 0
(0 2900);
DISPLAY 0.872340 (0 2900);
PAINT GREEN (0 2900);
DISPLAY INVISIBLE (0 2900);
FORCEPROP 1 LAST HDL_TAP TRUE
J 0
(325 2725);
DISPLAY 0.872340 (325 2725);
DISPLAY INVISIBLE (325 2725);
FORCEPROP 1 LAST PATH I87
J 0
(-2 2850);
DISPLAY 0.872340 (-2 2850);
PAINT GREEN (-2 2850);
DISPLAY INVISIBLE (-2 2850);
FORCEADD TAP..1
(0 3000);
FORCEPROP 3 LASTPIN (-50 3000) SIG_NAME M_A_CPU0_SA_DQ<7>
J 0
(-40 3010);
DISPLAY 0.659574 (-40 3010);
PAINT MONO (-40 3010);
DISPLAY INVISIBLE (-40 3010);
FORCEPROP 1 LASTPIN (-50 3000) BN 7
J 0
(-62 3008);
DISPLAY 0.680851 (-62 3008);
PAINT GREEN (-62 3008);
FORCEPROP 2 LAST CDS_LIB standard
J 0
(0 3000);
PAINT MONO (0 3000);
DISPLAY INVISIBLE (0 3000);
FORCEPROP 1 LAST BODY_TYPE PLUMBING
J 0
(0 3050);
DISPLAY 0.872340 (0 3050);
PAINT GREEN (0 3050);
DISPLAY INVISIBLE (0 3050);
FORCEPROP 1 LAST HDL_TAP TRUE
J 0
(325 2875);
DISPLAY 0.872340 (325 2875);
DISPLAY INVISIBLE (325 2875);
FORCEPROP 1 LAST PATH I88
J 0
(-2 3000);
DISPLAY 0.872340 (-2 3000);
PAINT GREEN (-2 3000);
DISPLAY INVISIBLE (-2 3000);
FORCEADD TAP..1
(0 3050);
FORCEPROP 3 LASTPIN (-50 3050) SIG_NAME M_A_CPU0_SA_DQ<8>
J 0
(-40 3060);
DISPLAY 0.659574 (-40 3060);
PAINT MONO (-40 3060);
DISPLAY INVISIBLE (-40 3060);
FORCEPROP 1 LASTPIN (-50 3050) BN 8
J 0
(-62 3058);
DISPLAY 0.680851 (-62 3058);
PAINT GREEN (-62 3058);
FORCEPROP 2 LAST CDS_LIB standard
J 0
(0 3050);
PAINT MONO (0 3050);
DISPLAY INVISIBLE (0 3050);
FORCEPROP 1 LAST BODY_TYPE PLUMBING
J 0
(0 3100);
DISPLAY 0.872340 (0 3100);
PAINT GREEN (0 3100);
DISPLAY INVISIBLE (0 3100);
FORCEPROP 1 LAST HDL_TAP TRUE
J 0
(325 2925);
DISPLAY 0.872340 (325 2925);
DISPLAY INVISIBLE (325 2925);
FORCEPROP 1 LAST PATH I89
J 0
(-2 3050);
DISPLAY 0.872340 (-2 3050);
PAINT GREEN (-2 3050);
DISPLAY INVISIBLE (-2 3050);
FORCEADD OFFPAGE..1
(-2575 1950);
FORCEPROP 2 LAST $XR3 85 
J 0
(-3127 1950);
DISPLAY 0.638298 (-3127 1950);
PAINT MONO (-3127 1950);
FORCEPROP 2 LAST $XR2 84 
J 0
(-3037 1950);
DISPLAY 0.638298 (-3037 1950);
PAINT MONO (-3037 1950);
FORCEPROP 2 LAST $XR1 82 
J 0
(-2947 1950);
DISPLAY 0.638298 (-2947 1950);
PAINT MONO (-2947 1950);
FORCEPROP 2 LAST $XR0 129 
J 0
(-2857 1950);
DISPLAY 0.638298 (-2857 1950);
PAINT MONO (-2857 1950);
FORCEPROP 2 LAST CDS_LIB standard
J 0
(-2575 1950);
PAINT MONO (-2575 1950);
DISPLAY INVISIBLE (-2575 1950);
FORCEPROP 1 LAST OFFPAGE TRUE
J 0
(-2250 1825);
DISPLAY 0.872340 (-2250 1825);
DISPLAY INVISIBLE (-2250 1825);
FORCEPROP 1 LAST COMMENT_BODY TRUE
J 0
(-2450 1850);
DISPLAY 0.872340 (-2450 1850);
PAINT GREEN (-2450 1850);
DISPLAY INVISIBLE (-2450 1850);
FORCEPROP 2 LAST PATH I9
J 0
(-2525 2025);
DISPLAY 1.021277 (-2525 2025);
DISPLAY INVISIBLE (-2525 2025);
FORCEADD TAP..1
(0 3100);
FORCEPROP 3 LASTPIN (-50 3100) SIG_NAME M_A_CPU0_SA_DQ<9>
J 0
(-40 3110);
DISPLAY 0.659574 (-40 3110);
PAINT MONO (-40 3110);
DISPLAY INVISIBLE (-40 3110);
FORCEPROP 1 LASTPIN (-50 3100) BN 9
J 0
(-62 3108);
DISPLAY 0.680851 (-62 3108);
PAINT GREEN (-62 3108);
FORCEPROP 2 LAST CDS_LIB standard
J 0
(0 3100);
PAINT MONO (0 3100);
DISPLAY INVISIBLE (0 3100);
FORCEPROP 1 LAST BODY_TYPE PLUMBING
J 0
(0 3150);
DISPLAY 0.872340 (0 3150);
PAINT GREEN (0 3150);
DISPLAY INVISIBLE (0 3150);
FORCEPROP 1 LAST HDL_TAP TRUE
J 0
(325 2975);
DISPLAY 0.872340 (325 2975);
DISPLAY INVISIBLE (325 2975);
FORCEPROP 1 LAST PATH I90
J 0
(-2 3100);
DISPLAY 0.872340 (-2 3100);
PAINT GREEN (-2 3100);
DISPLAY INVISIBLE (-2 3100);
FORCEADD TAP..1
(0 3150);
FORCEPROP 3 LASTPIN (-50 3150) SIG_NAME M_A_CPU0_SA_DQ<10>
J 0
(-40 3160);
DISPLAY 0.659574 (-40 3160);
PAINT MONO (-40 3160);
DISPLAY INVISIBLE (-40 3160);
FORCEPROP 1 LASTPIN (-50 3150) BN 10
J 0
(-62 3158);
DISPLAY 0.680851 (-62 3158);
PAINT GREEN (-62 3158);
FORCEPROP 2 LAST CDS_LIB standard
J 0
(0 3150);
PAINT MONO (0 3150);
DISPLAY INVISIBLE (0 3150);
FORCEPROP 1 LAST BODY_TYPE PLUMBING
J 0
(0 3200);
DISPLAY 0.872340 (0 3200);
PAINT GREEN (0 3200);
DISPLAY INVISIBLE (0 3200);
FORCEPROP 1 LAST HDL_TAP TRUE
J 0
(325 3025);
DISPLAY 0.872340 (325 3025);
DISPLAY INVISIBLE (325 3025);
FORCEPROP 1 LAST PATH I91
J 0
(-2 3150);
DISPLAY 0.872340 (-2 3150);
PAINT GREEN (-2 3150);
DISPLAY INVISIBLE (-2 3150);
FORCEADD TAP..1
(0 3200);
FORCEPROP 3 LASTPIN (-50 3200) SIG_NAME M_A_CPU0_SA_DQ<11>
J 0
(-40 3210);
DISPLAY 0.659574 (-40 3210);
PAINT MONO (-40 3210);
DISPLAY INVISIBLE (-40 3210);
FORCEPROP 1 LASTPIN (-50 3200) BN 11
J 0
(-62 3208);
DISPLAY 0.680851 (-62 3208);
PAINT GREEN (-62 3208);
FORCEPROP 2 LAST CDS_LIB standard
J 0
(0 3200);
PAINT MONO (0 3200);
DISPLAY INVISIBLE (0 3200);
FORCEPROP 1 LAST BODY_TYPE PLUMBING
J 0
(0 3250);
DISPLAY 0.872340 (0 3250);
PAINT GREEN (0 3250);
DISPLAY INVISIBLE (0 3250);
FORCEPROP 1 LAST HDL_TAP TRUE
J 0
(325 3075);
DISPLAY 0.872340 (325 3075);
DISPLAY INVISIBLE (325 3075);
FORCEPROP 1 LAST PATH I92
J 0
(-2 3200);
DISPLAY 0.872340 (-2 3200);
PAINT GREEN (-2 3200);
DISPLAY INVISIBLE (-2 3200);
FORCEADD TAP..1
(0 3300);
FORCEPROP 3 LASTPIN (-50 3300) SIG_NAME M_A_CPU0_SA_DQ<13>
J 0
(-40 3310);
DISPLAY 0.659574 (-40 3310);
PAINT MONO (-40 3310);
DISPLAY INVISIBLE (-40 3310);
FORCEPROP 1 LASTPIN (-50 3300) BN 13
J 0
(-62 3308);
DISPLAY 0.680851 (-62 3308);
PAINT GREEN (-62 3308);
FORCEPROP 2 LAST CDS_LIB standard
J 0
(0 3300);
PAINT MONO (0 3300);
DISPLAY INVISIBLE (0 3300);
FORCEPROP 1 LAST BODY_TYPE PLUMBING
J 0
(0 3350);
DISPLAY 0.872340 (0 3350);
PAINT GREEN (0 3350);
DISPLAY INVISIBLE (0 3350);
FORCEPROP 1 LAST HDL_TAP TRUE
J 0
(325 3175);
DISPLAY 0.872340 (325 3175);
DISPLAY INVISIBLE (325 3175);
FORCEPROP 1 LAST PATH I93
J 0
(-2 3300);
DISPLAY 0.872340 (-2 3300);
PAINT GREEN (-2 3300);
DISPLAY INVISIBLE (-2 3300);
FORCEADD TAP..1
(0 3250);
FORCEPROP 3 LASTPIN (-50 3250) SIG_NAME M_A_CPU0_SA_DQ<12>
J 0
(-40 3260);
DISPLAY 0.659574 (-40 3260);
PAINT MONO (-40 3260);
DISPLAY INVISIBLE (-40 3260);
FORCEPROP 1 LASTPIN (-50 3250) BN 12
J 0
(-62 3258);
DISPLAY 0.680851 (-62 3258);
PAINT GREEN (-62 3258);
FORCEPROP 2 LAST CDS_LIB standard
J 0
(0 3250);
PAINT MONO (0 3250);
DISPLAY INVISIBLE (0 3250);
FORCEPROP 1 LAST BODY_TYPE PLUMBING
J 0
(0 3300);
DISPLAY 0.872340 (0 3300);
PAINT GREEN (0 3300);
DISPLAY INVISIBLE (0 3300);
FORCEPROP 1 LAST HDL_TAP TRUE
J 0
(325 3125);
DISPLAY 0.872340 (325 3125);
DISPLAY INVISIBLE (325 3125);
FORCEPROP 1 LAST PATH I94
J 0
(-2 3250);
DISPLAY 0.872340 (-2 3250);
PAINT GREEN (-2 3250);
DISPLAY INVISIBLE (-2 3250);
FORCEADD TAP..1
(0 3350);
FORCEPROP 3 LASTPIN (-50 3350) SIG_NAME M_A_CPU0_SA_DQ<14>
J 0
(-40 3360);
DISPLAY 0.659574 (-40 3360);
PAINT MONO (-40 3360);
DISPLAY INVISIBLE (-40 3360);
FORCEPROP 1 LASTPIN (-50 3350) BN 14
J 0
(-62 3358);
DISPLAY 0.680851 (-62 3358);
PAINT GREEN (-62 3358);
FORCEPROP 2 LAST CDS_LIB standard
J 0
(0 3350);
PAINT MONO (0 3350);
DISPLAY INVISIBLE (0 3350);
FORCEPROP 1 LAST BODY_TYPE PLUMBING
J 0
(0 3400);
DISPLAY 0.872340 (0 3400);
PAINT GREEN (0 3400);
DISPLAY INVISIBLE (0 3400);
FORCEPROP 1 LAST HDL_TAP TRUE
J 0
(325 3225);
DISPLAY 0.872340 (325 3225);
DISPLAY INVISIBLE (325 3225);
FORCEPROP 1 LAST PATH I95
J 0
(-2 3350);
DISPLAY 0.872340 (-2 3350);
PAINT GREEN (-2 3350);
DISPLAY INVISIBLE (-2 3350);
FORCEADD TAP..1
(0 3450);
FORCEPROP 3 LASTPIN (-50 3450) SIG_NAME M_A_CPU0_SA_DQ<16>
J 0
(-40 3460);
DISPLAY 0.659574 (-40 3460);
PAINT MONO (-40 3460);
DISPLAY INVISIBLE (-40 3460);
FORCEPROP 1 LASTPIN (-50 3450) BN 16
J 0
(-62 3458);
DISPLAY 0.680851 (-62 3458);
PAINT GREEN (-62 3458);
FORCEPROP 2 LAST CDS_LIB standard
J 0
(0 3450);
PAINT MONO (0 3450);
DISPLAY INVISIBLE (0 3450);
FORCEPROP 1 LAST BODY_TYPE PLUMBING
J 0
(0 3500);
DISPLAY 0.872340 (0 3500);
PAINT GREEN (0 3500);
DISPLAY INVISIBLE (0 3500);
FORCEPROP 1 LAST HDL_TAP TRUE
J 0
(325 3325);
DISPLAY 0.872340 (325 3325);
DISPLAY INVISIBLE (325 3325);
FORCEPROP 1 LAST PATH I96
J 0
(-2 3450);
DISPLAY 0.872340 (-2 3450);
PAINT GREEN (-2 3450);
DISPLAY INVISIBLE (-2 3450);
FORCEADD TAP..1
(0 3400);
FORCEPROP 3 LASTPIN (-50 3400) SIG_NAME M_A_CPU0_SA_DQ<15>
J 0
(-40 3410);
DISPLAY 0.659574 (-40 3410);
PAINT MONO (-40 3410);
DISPLAY INVISIBLE (-40 3410);
FORCEPROP 1 LASTPIN (-50 3400) BN 15
J 0
(-62 3408);
DISPLAY 0.680851 (-62 3408);
PAINT GREEN (-62 3408);
FORCEPROP 2 LAST CDS_LIB standard
J 0
(0 3400);
PAINT MONO (0 3400);
DISPLAY INVISIBLE (0 3400);
FORCEPROP 1 LAST BODY_TYPE PLUMBING
J 0
(0 3450);
DISPLAY 0.872340 (0 3450);
PAINT GREEN (0 3450);
DISPLAY INVISIBLE (0 3450);
FORCEPROP 1 LAST HDL_TAP TRUE
J 0
(325 3275);
DISPLAY 0.872340 (325 3275);
DISPLAY INVISIBLE (325 3275);
FORCEPROP 1 LAST PATH I97
J 0
(-2 3400);
DISPLAY 0.872340 (-2 3400);
PAINT GREEN (-2 3400);
DISPLAY INVISIBLE (-2 3400);
FORCEADD TAP..1
(0 3600);
FORCEPROP 3 LASTPIN (-50 3600) SIG_NAME M_A_CPU0_SA_DQ<19>
J 0
(-40 3610);
DISPLAY 0.659574 (-40 3610);
PAINT MONO (-40 3610);
DISPLAY INVISIBLE (-40 3610);
FORCEPROP 1 LASTPIN (-50 3600) BN 19
J 0
(-62 3608);
DISPLAY 0.680851 (-62 3608);
PAINT GREEN (-62 3608);
FORCEPROP 2 LAST CDS_LIB standard
J 0
(0 3600);
PAINT MONO (0 3600);
DISPLAY INVISIBLE (0 3600);
FORCEPROP 1 LAST BODY_TYPE PLUMBING
J 0
(0 3650);
DISPLAY 0.872340 (0 3650);
PAINT GREEN (0 3650);
DISPLAY INVISIBLE (0 3650);
FORCEPROP 1 LAST HDL_TAP TRUE
J 0
(325 3475);
DISPLAY 0.872340 (325 3475);
DISPLAY INVISIBLE (325 3475);
FORCEPROP 1 LAST PATH I98
J 0
(-2 3600);
DISPLAY 0.872340 (-2 3600);
PAINT GREEN (-2 3600);
DISPLAY INVISIBLE (-2 3600);
FORCEADD TAP..1
(0 3500);
FORCEPROP 3 LASTPIN (-50 3500) SIG_NAME M_A_CPU0_SA_DQ<17>
J 0
(-40 3510);
DISPLAY 0.659574 (-40 3510);
PAINT MONO (-40 3510);
DISPLAY INVISIBLE (-40 3510);
FORCEPROP 1 LASTPIN (-50 3500) BN 17
J 0
(-62 3508);
DISPLAY 0.680851 (-62 3508);
PAINT GREEN (-62 3508);
FORCEPROP 2 LAST CDS_LIB standard
J 0
(0 3500);
PAINT MONO (0 3500);
DISPLAY INVISIBLE (0 3500);
FORCEPROP 1 LAST BODY_TYPE PLUMBING
J 0
(0 3550);
DISPLAY 0.872340 (0 3550);
PAINT GREEN (0 3550);
DISPLAY INVISIBLE (0 3550);
FORCEPROP 1 LAST HDL_TAP TRUE
J 0
(325 3375);
DISPLAY 0.872340 (325 3375);
DISPLAY INVISIBLE (325 3375);
FORCEPROP 1 LAST PATH I99
J 0
(-2 3500);
DISPLAY 0.872340 (-2 3500);
PAINT GREEN (-2 3500);
DISPLAY INVISIBLE (-2 3500);
FORCEADD CAD_NOTE..1
(1850 -250);
FORCEPROP 0 LAST S1 PLACE THE BYPASS CAPS CLOSE TO DIMM
J 0
(1725 -375);
DISPLAY 1.021277 (1725 -375);
PAINT WHITE (1725 -375);
FORCEPROP 2 LAST CDS_LIB logical_power
J 0
(1850 -250);
PAINT MONO (1850 -250);
DISPLAY INVISIBLE (1850 -250);
FORCEPROP 1 LAST COMMENT_BODY TRUE
J 0
(1875 -150);
DISPLAY 0.978723 (1875 -150);
DISPLAY INVISIBLE (1875 -150);
FORCEADD BOM_NOTE..1
(-1125 -625);
FORCEPROP 0 LAST S1 BOM NOTE: 2ND SOURCE IS DFHST8FS384 (@BLACK)
J 0
(-1275 -775);
DISPLAY 0.808511 (-1275 -775);
PAINT SKYBLUE (-1275 -775);
FORCEPROP 2 LAST CDS_LIB logical_power
J 0
(-1125 -625);
DISPLAY INVISIBLE (-1125 -625);
FORCEPROP 1 LAST COMMENT_BODY TRUE
J 0
(-1100 -525);
DISPLAY 0.978723 (-1100 -525);
DISPLAY INVISIBLE (-1100 -525);
FORCEADD QUANTA_TITLE_BLOCK_C..1
(6125 -1550);
FORCEPROP 0 LAST CDS_CON_LAST_MODIFIED Fri Aug 25 14:01:02 2023
J 0
(4240 -1535);
PAINT MONO (4240 -1535);
DISPLAY INVISIBLE (4240 -1535);
FORCEPROP 1 LAST CUSTOM_TXT_CDS <CON_LAST_MODIFIED>
J 0
(4240 -1535);
DISPLAY 0.978723 (4240 -1535);
FORCEPROP 2 LAST CUSTOM_TXT_CDS <XR_PAGE_TITLE>
J 0
(-1765 3700);
DISPLAY 0.638298 (-1765 3700);
PAINT PINK (-1765 3700);
DISPLAY INVISIBLE (-1765 3700);
FORCEPROP 2 LAST CUSTOM_TXT_CDS <Q_NUMBER>
J 0
(4722 -1447);
DISPLAY 1.212766 (4722 -1447);
FORCEPROP 1 LAST CUSTOM_TXT_CDS <NAME_2>
J 0
(2950 -1500);
FORCEPROP 1 LAST CUSTOM_TXT_CDS <NAME_1>
J 0
(2950 -1375);
FORCEPROP 1 LAST CUSTOM_TXT_CDS <Q_PROJ>
J 0
(3743 -1448);
DISPLAY 1.212766 (3743 -1448);
FORCEPROP 1 LAST CUSTOM_TXT_CDS <Q_REV>
J 0
(5941 -1447);
DISPLAY 1.212766 (5941 -1447);
FORCEPROP 1 LAST CUSTOM_TXT_CDS <CON_PAGE_NUM> OF <CON_TOTAL_PAGES>
J 0
(5679 -1532);
DISPLAY 0.978723 (5679 -1532);
FORCEPROP 1 LAST Q_TITLE DDR5 - CPU0 CHA DIMM2(BLACK)
J 0
(-3241 -1524);
DISPLAY 2.446809 (-3241 -1524);
PAINT GREEN (-3241 -1524);
FORCEPROP 1 LAST Q_DEPT 
J 1
(2362 -1501);
DISPLAY 1.957447 (2362 -1501);
PAINT GREEN (2362 -1501);
FORCEPROP 1 LAST COMMENT_BODY TRUE
J 0
(6137 -1563);
DISPLAY 0.978723 (6137 -1563);
PAINT GREEN (6137 -1563);
DISPLAY INVISIBLE (6137 -1563);
FORCEPROP 2 LAST CDS_XR_PAGE_TITLE CR-83 : @S9S_MB_2U_LIB.S9S_MB_2U(SCH_1):PAGE83
J 0
(-1765 3700);
DISPLAY 0.638298 (-1765 3700);
PAINT PINK (-1765 3700);
DISPLAY INVISIBLE (-1765 3700);
FORCEPROP 2 LAST CDS_LIB pure_quanta
J 0
(6125 -1550);
PAINT MONO (6125 -1550);
DISPLAY INVISIBLE (6125 -1550);
FORCEPROP 1 LAST CDS_LMAN_SYM_OUTLINE -9475,6775,100,-125
J 0
(6125 -1550);
DISPLAY 0.468085 (6125 -1550);
PAINT GREEN (6125 -1550);
DISPLAY INVISIBLE (6125 -1550);
FORCEPROP 2 LAST PAGE_BORDER TRUE
J 0
(-1765 3700);
DISPLAY 0.638298 (-1765 3700);
PAINT PINK (-1765 3700);
DISPLAY INVISIBLE (-1765 3700);
WIRE 17 -1 (2775 3075)(2775 3175);
WIRE 17 -1 (2775 2975)(2775 3075);
WIRE 17 -1 (2775 3175)(3800 3175);
FORCEPROP 2 LAST SIG_NAME M_A_CPU0_SB_DQS_DP<9:0>
J 0
(3015 3185);
DISPLAY 0.680851 (3015 3185);
PAINT WHITE (3015 3185);
WIRE 17 -1 (2950 3025)(2950 3125);
WIRE 17 -1 (2950 2925)(2950 3025);
WIRE 17 -1 (2950 3125)(3800 3125);
FORCEPROP 2 LAST SIG_NAME M_A_CPU0_SB_DQS_DN<9:0>
J 0
(3015 3135);
DISPLAY 0.680851 (3015 3135);
PAINT WHITE (3015 3135);
WIRE 17 -1 (2775 4125)(2775 4225);
WIRE 17 -1 (2775 4025)(2775 4125);
WIRE 17 -1 (2775 4225)(3800 4225);
FORCEPROP 2 LAST SIG_NAME M_A_CPU0_SA_DQS_DP<9:0>
J 0
(3015 4235);
DISPLAY 0.680851 (3015 4235);
PAINT WHITE (3015 4235);
WIRE 17 -1 (2950 4075)(2950 4175);
WIRE 17 -1 (2950 3975)(2950 4075);
WIRE 17 -1 (2950 4175)(3800 4175);
FORCEPROP 2 LAST SIG_NAME M_A_CPU0_SA_DQS_DN<9:0>
J 0
(3015 4185);
DISPLAY 0.680851 (3015 4185);
PAINT WHITE (3015 4185);
WIRE 17 -1 (2950 2825)(2950 2925);
WIRE 17 -1 (2775 3925)(2775 4025);
WIRE 17 -1 (2775 2875)(2775 2975);
WIRE 17 -1 (2775 2775)(2775 2875);
WIRE 17 -1 (2775 2675)(2775 2775);
WIRE 17 -1 (2775 2675)(2775 2575);
WIRE 17 -1 (2950 2725)(2950 2825);
WIRE 17 -1 (2950 2625)(2950 2725);
WIRE 17 -1 (2950 2625)(2950 2525);
WIRE 17 -1 (2950 3875)(2950 3975);
WIRE 17 -1 (2950 3775)(2950 3875);
WIRE 17 -1 (2950 3675)(2950 3775);
WIRE 17 -1 (2950 3675)(2950 3575);
WIRE 17 -1 (2775 2475)(2775 2575);
WIRE 17 -1 (2950 2425)(2950 2525);
WIRE 17 -1 (2775 3825)(2775 3925);
WIRE 17 -1 (2775 3725)(2775 3825);
WIRE 17 -1 (2775 3725)(2775 3625);
WIRE 17 -1 (2775 3525)(2775 3625);
WIRE 17 -1 (2950 3475)(2950 3575);
WIRE 17 -1 (2775 2375)(2775 2475);
WIRE 17 -1 (2775 2275)(2775 2375);
WIRE 17 -1 (2950 2325)(2950 2425);
WIRE 17 -1 (2950 2225)(2950 2325);
WIRE 17 -1 (2775 3425)(2775 3525);
WIRE 17 -1 (2775 3325)(2775 3425);
WIRE 17 -1 (2950 3375)(2950 3475);
WIRE 17 -1 (2950 3275)(2950 3375);
WIRE 17 -1 (50 1025)(50 1075);
WIRE 17 -1 (50 1075)(50 1125);
WIRE 17 -1 (50 1125)(50 1175);
WIRE 17 -1 (50 1175)(50 1225);
WIRE 17 -1 (50 1225)(50 1275);
WIRE 17 -1 (50 1275)(50 1325);
WIRE 17 -1 (50 1325)(50 1375);
WIRE 17 -1 (50 1375)(50 1425);
WIRE 17 -1 (50 1425)(50 1475);
WIRE 17 -1 (50 1475)(50 1525);
WIRE 17 -1 (50 1525)(50 1575);
WIRE 17 -1 (50 1575)(50 1625);
WIRE 17 -1 (50 1625)(50 1675);
WIRE 17 -1 (50 1675)(50 1725);
WIRE 17 -1 (50 1725)(50 1775);
WIRE 17 -1 (50 1775)(50 1825);
WIRE 17 -1 (50 1825)(50 1875);
WIRE 17 -1 (50 1875)(50 1925);
WIRE 17 -1 (50 1925)(50 1975);
WIRE 17 -1 (50 1975)(50 2025);
WIRE 17 -1 (50 2025)(50 2075);
WIRE 17 -1 (50 2075)(50 2125);
WIRE 17 -1 (50 2125)(50 2175);
WIRE 17 -1 (50 2175)(50 2225);
WIRE 17 -1 (50 2225)(50 2275);
WIRE 17 -1 (50 2275)(50 2325);
WIRE 17 -1 (50 2325)(50 2375);
WIRE 17 -1 (50 2375)(50 2425);
WIRE 17 -1 (50 2425)(50 2475);
WIRE 17 -1 (50 2475)(50 2525);
WIRE 17 -1 (50 2525)(50 2575);
WIRE 17 -1 (50 2575)(775 2575);
FORCEPROP 2 LAST SIG_NAME M_A_CPU0_SB_DQ<31:0>
J 0
(115 2585);
DISPLAY 0.680851 (115 2585);
PAINT WHITE (115 2585);
WIRE 17 -1 (50 2675)(50 2725);
WIRE 17 -1 (50 2725)(50 2775);
WIRE 17 -1 (50 2775)(50 2825);
WIRE 17 -1 (50 2825)(50 2875);
WIRE 17 -1 (50 2875)(50 2925);
WIRE 17 -1 (50 2925)(50 2975);
WIRE 17 -1 (50 2975)(50 3025);
WIRE 17 -1 (50 3025)(50 3075);
WIRE 17 -1 (50 3075)(50 3125);
WIRE 17 -1 (50 3125)(50 3175);
WIRE 17 -1 (50 3175)(50 3225);
WIRE 17 -1 (50 3225)(50 3275);
WIRE 17 -1 (50 3275)(50 3325);
WIRE 17 -1 (50 3325)(50 3375);
WIRE 17 -1 (50 3375)(50 3425);
WIRE 17 -1 (50 3425)(50 3475);
WIRE 17 -1 (50 3475)(50 3525);
WIRE 17 -1 (50 3525)(50 3575);
WIRE 17 -1 (50 3575)(50 3625);
WIRE 17 -1 (50 3625)(50 3675);
WIRE 17 -1 (50 3675)(50 3725);
WIRE 17 -1 (50 3725)(50 3775);
WIRE 17 -1 (50 3775)(50 3825);
WIRE 17 -1 (50 3825)(50 3875);
WIRE 17 -1 (50 3875)(50 3925);
WIRE 17 -1 (50 3925)(50 3975);
WIRE 17 -1 (50 3975)(50 4025);
WIRE 17 -1 (50 4025)(50 4075);
WIRE 17 -1 (50 4075)(50 4125);
WIRE 17 -1 (50 4125)(50 4175);
WIRE 17 -1 (50 4175)(50 4225);
WIRE 17 -1 (50 4225)(775 4225);
FORCEPROP 2 LAST SIG_NAME M_A_CPU0_SA_DQ<31:0>
J 0
(115 4235);
DISPLAY 0.680851 (115 4235);
PAINT WHITE (115 4235);
WIRE 17 -1 (-1700 2025)(-1700 2075);
WIRE 17 -1 (-1700 2075)(-1700 2125);
WIRE 17 -1 (-1700 2125)(-1700 2175);
WIRE 17 -1 (-1700 2175)(-1700 2225);
WIRE 17 -1 (-1700 2225)(-1700 2275);
WIRE 17 -1 (-1700 2275)(-1700 2325);
WIRE 17 -1 (-1700 2325)(-1700 2375);
WIRE 17 -1 (-2525 2375)(-1700 2375);
FORCEPROP 2 LAST SIG_NAME M_A_CPU0_SB_CB<7:0>
J 0
(-2435 2385);
DISPLAY 0.680851 (-2435 2385);
PAINT WHITE (-2435 2385);
WIRE 17 -1 (-1700 2475)(-1700 2525);
WIRE 17 -1 (-1700 2525)(-1700 2575);
WIRE 17 -1 (-1700 2575)(-1700 2625);
WIRE 17 -1 (-1700 2625)(-1700 2675);
WIRE 17 -1 (-1700 2675)(-1700 2725);
WIRE 17 -1 (-1700 2725)(-1700 2775);
WIRE 17 -1 (-1700 2775)(-1700 2825);
WIRE 17 -1 (-2525 2825)(-1700 2825);
FORCEPROP 2 LAST SIG_NAME M_A_CPU0_SA_CB<7:0>
J 0
(-2435 2835);
DISPLAY 0.680851 (-2435 2835);
PAINT WHITE (-2435 2835);
WIRE 17 -1 (-2525 3825)(-1700 3825);
FORCEPROP 2 LAST SIG_NAME M_A_CPU0_SB_CA<6:0>
J 0
(-2435 3835);
DISPLAY 0.680851 (-2435 3835);
PAINT WHITE (-2435 3835);
WIRE 17 -1 (-2525 4225)(-1700 4225);
FORCEPROP 2 LAST SIG_NAME M_A_CPU0_SA_CA<6:0>
J 0
(-2435 4235);
DISPLAY 0.680851 (-2435 4235);
PAINT WHITE (-2435 4235);
WIRE 17 -1 (-1700 3775)(-1700 3825);
WIRE 17 -1 (-1700 3725)(-1700 3775);
WIRE 17 -1 (-1700 4175)(-1700 4225);
WIRE 17 -1 (-1700 4125)(-1700 4175);
WIRE 17 -1 (-1700 3675)(-1700 3725);
WIRE 17 -1 (-1700 4075)(-1700 4125);
WIRE 17 -1 (-1700 3625)(-1700 3675);
WIRE 17 -1 (-1700 3575)(-1700 3625);
WIRE 17 -1 (-1700 3525)(-1700 3575);
WIRE 17 -1 (-1700 4025)(-1700 4075);
WIRE 17 -1 (-1700 3975)(-1700 4025);
WIRE 17 -1 (-1700 3925)(-1700 3975);
WIRE 16 -1 (-2475 2025)(-2475 1750);
WIRE 16 -1 (1725 425)(1725 600);
WIRE 16 -1 (2725 600)(2725 550);
WIRE 16 -1 (4350 4700)(4350 4200);
WIRE 16 -1 (-1425 -125)(-1425 -50);
WIRE 16 -1 (1725 225)(1725 0);
WIRE 16 -1 (3350 0)(3350 75);
WIRE 16 -1 (6050 850)(6050 550);
WIRE 16 -1 (6050 900)(6050 850);
WIRE 16 -1 (5800 850)(6050 850);
WIRE 16 -1 (4350 550)(4350 950);
WIRE 16 3135 (1375 825)(1375 -475);
WIRE 16 3135 (3975 825)(1375 825);
WIRE 16 3135 (1375 -475)(3975 -475);
WIRE 16 3135 (3975 -475)(3975 825);
WIRE 16 -1 (-2475 1750)(-1425 1750);
WIRE 16 -1 (-1425 1850)(-2525 1850);
FORCEPROP 2 LAST SIG_NAME M_A_CPU0_ALERT_N
J 0
(-2437 1859);
DISPLAY 0.680851 (-2437 1859);
PAINT WHITE (-2437 1859);
WIRE 16 -1 (-2925 1500)(-2750 1500);
WIRE 16 -1 (-2925 1600)(-2925 1500);
WIRE 16 -1 (-2925 1600)(-1425 1600);
FORCEPROP 2 LAST SIG_NAME I3C_SPD_DDRABCD_CPU0_LVC1_SCL_R2
J 0
(-2485 1610);
DISPLAY 0.680851 (-2485 1610);
PAINT WHITE (-2485 1610);
WIRE 16 -1 (-1425 1650)(-2425 1650);
FORCEPROP 2 LAST SIG_NAME I3C_SPD_DDRABCD_CPU0_LVC1_SDA
J 0
(-2435 1660);
DISPLAY 0.680851 (-2435 1660);
PAINT WHITE (-2435 1660);
WIRE 16 -1 (-1425 1700)(-2425 1700);
FORCEPROP 2 LAST SIG_NAME PD_CHA_CPU0_DIMM2_SAA
J 0
(-2337 1709);
DISPLAY 0.680851 (-2337 1709);
PAINT WHITE (-2337 1709);
WIRE 16 -1 (-1800 1950)(-2525 1950);
FORCEPROP 2 LAST SIG_NAME RST_M_AB_CPU0_FPGA_N
J 0
(-2437 1959);
DISPLAY 0.680851 (-2437 1959);
PAINT WHITE (-2437 1959);
WIRE 16 -1 (-1800 1950)(-1800 1900);
WIRE 16 -1 (-1800 1900)(-1425 1900);
WIRE 16 -1 (-1400 1450)(-1500 1450);
WIRE 16 -1 (-1400 1500)(-1400 1450);
WIRE 16 -1 (-2550 1500)(-1400 1500);
FORCEPROP 2 LAST SIG_NAME I3C_SPD_DDRABCD_CPU0_LVC1_SCL
J 0
(-2360 1510);
DISPLAY 0.680851 (-2360 1510);
PAINT WHITE (-2360 1510);
WIRE 16 -1 (-1425 1350)(-2525 1350);
FORCEPROP 2 LAST SIG_NAME PWRGD_CHA_CPU0_DIMM2
J 0
(-2437 1359);
DISPLAY 0.680851 (-2437 1359);
PAINT WHITE (-2437 1359);
WIRE 16 -1 (-1425 1250)(-2525 1250);
FORCEPROP 2 LAST SIG_NAME TP_CHA_CPU0_DIMM2_FRU_6
J 0
(-2437 1259);
DISPLAY 0.680851 (-2437 1259);
PAINT WHITE (-2437 1259);
WIRE 16 -1 (-1425 1050)(-2525 1050);
FORCEPROP 2 LAST SIG_NAME TP_CHA_CPU0_DIMM2_FRU_2
J 0
(-2437 1059);
DISPLAY 0.680851 (-2437 1059);
PAINT WHITE (-2437 1059);
WIRE 16 -1 (-1425 950)(-2525 950);
FORCEPROP 2 LAST SIG_NAME TP_CHA_CPU0_DIMM2_FRU_0
J 0
(-2437 959);
DISPLAY 0.680851 (-2437 959);
PAINT WHITE (-2437 959);
WIRE 16 -1 (-225 2200)(-50 2200);
WIRE 16 -1 (2850 2200)(2575 2200);
WIRE 16 -1 (-1425 250)(-2525 250);
FORCEPROP 2 LAST SIG_NAME PD_CHA_CPU0_DIMM2_SAA
J 0
(-2437 259);
DISPLAY 0.680851 (-2437 259);
PAINT WHITE (-2437 259);
WIRE 16 -1 (-1425 150)(-1425 250);
WIRE 16 -1 (-1425 750)(-2525 750);
FORCEPROP 2 LAST SIG_NAME M_A_CPU0_SB_RSP<1>
J 0
(-2437 759);
DISPLAY 0.680851 (-2437 759);
PAINT WHITE (-2437 759);
WIRE 16 -1 (-1425 800)(-2525 800);
FORCEPROP 2 LAST SIG_NAME M_A_CPU0_SA_RSP<1>
J 0
(-2437 809);
DISPLAY 0.680851 (-2437 809);
PAINT WHITE (-2437 809);
WIRE 16 -1 (-1425 2950)(-2525 2950);
FORCEPROP 2 LAST SIG_NAME M_A_CPU0_CLK_DP<1>
J 0
(-2437 2959);
DISPLAY 0.680851 (-2437 2959);
PAINT WHITE (-2437 2959);
WIRE 16 -1 (-1425 2900)(-2525 2900);
FORCEPROP 2 LAST SIG_NAME M_A_CPU0_CLK_DN<1>
J 0
(-2437 2909);
DISPLAY 0.680851 (-2437 2909);
PAINT WHITE (-2437 2909);
WIRE 16 -1 (-1425 3050)(-2525 3050);
FORCEPROP 2 LAST SIG_NAME M_A_CPU0_SB_CS_N<2>
J 0
(-2437 3059);
DISPLAY 0.680851 (-2437 3059);
PAINT WHITE (-2437 3059);
WIRE 16 -1 (-1425 3100)(-2525 3100);
FORCEPROP 2 LAST SIG_NAME M_A_CPU0_SB_CS_N<3>
J 0
(-2437 3109);
DISPLAY 0.680851 (-2437 3109);
PAINT WHITE (-2437 3109);
WIRE 16 -1 (-1425 3250)(-2525 3250);
FORCEPROP 2 LAST SIG_NAME M_A_CPU0_SA_CS_N<3>
J 0
(-2437 3259);
DISPLAY 0.680851 (-2437 3259);
PAINT WHITE (-2437 3259);
WIRE 16 -1 (-1425 3200)(-2525 3200);
FORCEPROP 2 LAST SIG_NAME M_A_CPU0_SA_CS_N<2>
J 0
(-2437 3209);
DISPLAY 0.680851 (-2437 3209);
PAINT WHITE (-2437 3209);
WIRE 16 -1 (-1425 3350)(-2525 3350);
FORCEPROP 2 LAST SIG_NAME M_A_CPU0_SB_PAR
J 0
(-2437 3359);
DISPLAY 0.680851 (-2437 3359);
PAINT WHITE (-2437 3359);
WIRE 16 -1 (-1425 3400)(-2525 3400);
FORCEPROP 2 LAST SIG_NAME M_A_CPU0_SA_PAR
J 0
(-2437 3409);
DISPLAY 0.680851 (-2437 3409);
PAINT WHITE (-2437 3409);
WIRE 16 -1 (-225 4200)(-50 4200);
WIRE 16 -1 (-1600 2800)(-1425 2800);
WIRE 16 -1 (-1600 2650)(-1425 2650);
WIRE 16 -1 (-1600 2500)(-1425 2500);
WIRE 16 -1 (-1600 2350)(-1425 2350);
WIRE 16 -1 (-1600 3900)(-1425 3900);
WIRE 16 -1 (-1600 3500)(-1425 3500);
WIRE 16 -1 (-1600 3950)(-1425 3950);
WIRE 16 -1 (-1600 3550)(-1425 3550);
WIRE 16 -1 (-1600 4000)(-1425 4000);
WIRE 16 -1 (-1600 3600)(-1425 3600);
WIRE 16 -1 (-1600 4050)(-1425 4050);
WIRE 16 -1 (-1600 3650)(-1425 3650);
WIRE 16 -1 (-1600 4100)(-1425 4100);
WIRE 16 -1 (-1600 3700)(-1425 3700);
WIRE 16 -1 (-1600 4150)(-1425 4150);
WIRE 16 -1 (-1600 3750)(-1425 3750);
WIRE 16 -1 (-1600 4200)(-1425 4200);
WIRE 16 -1 (-1600 3800)(-1425 3800);
WIRE 16 -1 (-1600 2750)(-1425 2750);
WIRE 16 -1 (-1600 2700)(-1425 2700);
WIRE 16 -1 (-1600 2600)(-1425 2600);
WIRE 16 -1 (-1600 2550)(-1425 2550);
WIRE 16 -1 (-1600 2450)(-1425 2450);
WIRE 16 -1 (-1600 2300)(-1425 2300);
WIRE 16 -1 (-1600 2250)(-1425 2250);
WIRE 16 -1 (-1600 2200)(-1425 2200);
WIRE 16 -1 (-1600 2150)(-1425 2150);
WIRE 16 -1 (-1600 2100)(-1425 2100);
WIRE 16 -1 (-1600 2050)(-1425 2050);
WIRE 16 -1 (-1600 2000)(-1425 2000);
WIRE 16 -1 (-225 4150)(-50 4150);
WIRE 16 -1 (-225 4100)(-50 4100);
WIRE 16 -1 (-225 4050)(-50 4050);
WIRE 16 -1 (-225 4000)(-50 4000);
WIRE 16 -1 (-225 3950)(-50 3950);
WIRE 16 -1 (-225 3900)(-50 3900);
WIRE 16 -1 (-225 3850)(-50 3850);
WIRE 16 -1 (-225 3800)(-50 3800);
WIRE 16 -1 (-225 3750)(-50 3750);
WIRE 16 -1 (-225 3700)(-50 3700);
WIRE 16 -1 (-225 3650)(-50 3650);
WIRE 16 -1 (-225 3600)(-50 3600);
WIRE 16 -1 (-225 3550)(-50 3550);
WIRE 16 -1 (-225 3500)(-50 3500);
WIRE 16 -1 (-225 3450)(-50 3450);
WIRE 16 -1 (-225 3400)(-50 3400);
WIRE 16 -1 (-225 3350)(-50 3350);
WIRE 16 -1 (-225 3300)(-50 3300);
WIRE 16 -1 (-225 3250)(-50 3250);
WIRE 16 -1 (-225 3200)(-50 3200);
WIRE 16 -1 (-225 3150)(-50 3150);
WIRE 16 -1 (-225 3100)(-50 3100);
WIRE 16 -1 (-225 3050)(-50 3050);
WIRE 16 -1 (-225 3000)(-50 3000);
WIRE 16 -1 (-225 2950)(-50 2950);
WIRE 16 -1 (-225 2900)(-50 2900);
WIRE 16 -1 (-225 2850)(-50 2850);
WIRE 16 -1 (-225 2800)(-50 2800);
WIRE 16 -1 (-225 2750)(-50 2750);
WIRE 16 -1 (-225 2700)(-50 2700);
WIRE 16 -1 (-225 2650)(-50 2650);
WIRE 16 -1 (-225 2550)(-50 2550);
WIRE 16 -1 (-225 2500)(-50 2500);
WIRE 16 -1 (-225 2450)(-50 2450);
WIRE 16 -1 (-225 2400)(-50 2400);
WIRE 16 -1 (-225 2350)(-50 2350);
WIRE 16 -1 (-225 2300)(-50 2300);
WIRE 16 -1 (-225 2250)(-50 2250);
WIRE 16 -1 (-225 2150)(-50 2150);
WIRE 16 -1 (-225 2100)(-50 2100);
WIRE 16 -1 (-225 2050)(-50 2050);
WIRE 16 -1 (-225 2000)(-50 2000);
WIRE 16 -1 (-225 1950)(-50 1950);
WIRE 16 -1 (-225 1900)(-50 1900);
WIRE 16 -1 (-225 1850)(-50 1850);
WIRE 16 -1 (-225 1800)(-50 1800);
WIRE 16 -1 (-225 1750)(-50 1750);
WIRE 16 -1 (-225 1700)(-50 1700);
WIRE 16 -1 (-225 1650)(-50 1650);
WIRE 16 -1 (-225 1600)(-50 1600);
WIRE 16 -1 (-225 1550)(-50 1550);
WIRE 16 -1 (-225 1500)(-50 1500);
WIRE 16 -1 (-225 1450)(-50 1450);
WIRE 16 -1 (-225 1400)(-50 1400);
WIRE 16 -1 (-225 1350)(-50 1350);
WIRE 16 -1 (-225 1300)(-50 1300);
WIRE 16 -1 (-225 1250)(-50 1250);
WIRE 16 -1 (-225 1200)(-50 1200);
WIRE 16 -1 (-225 1150)(-50 1150);
WIRE 16 -1 (-225 1100)(-50 1100);
WIRE 16 -1 (-225 1050)(-50 1050);
WIRE 16 -1 (-225 1000)(-50 1000);
WIRE 16 -1 (-1425 1200)(-2525 1200);
FORCEPROP 2 LAST SIG_NAME TP_CHA_CPU0_DIMM2_FRU_5
J 0
(-2437 1209);
DISPLAY 0.680851 (-2437 1209);
PAINT WHITE (-2437 1209);
WIRE 16 -1 (-1425 1150)(-2525 1150);
FORCEPROP 2 LAST SIG_NAME TP_CHA_CPU0_DIMM2_FRU_4
J 0
(-2437 1159);
DISPLAY 0.680851 (-2437 1159);
PAINT WHITE (-2437 1159);
WIRE 16 -1 (-1425 1100)(-2525 1100);
FORCEPROP 2 LAST SIG_NAME TP_CHA_CPU0_DIMM2_FRU_3
J 0
(-2437 1109);
DISPLAY 0.680851 (-2437 1109);
PAINT WHITE (-2437 1109);
WIRE 16 -1 (-1425 1000)(-2525 1000);
FORCEPROP 2 LAST SIG_NAME TP_CHA_CPU0_DIMM2_FRU_1
J 0
(-2437 1009);
DISPLAY 0.680851 (-2437 1009);
PAINT WHITE (-2437 1009);
WIRE 16 -1 (2850 3950)(2575 3950);
WIRE 16 -1 (2675 3900)(2575 3900);
WIRE 16 -1 (2675 3050)(2575 3050);
WIRE 16 -1 (2850 3000)(2575 3000);
WIRE 16 -1 (2675 2950)(2575 2950);
WIRE 16 -1 (2850 3250)(2575 3250);
WIRE 16 -1 (2675 3300)(2575 3300);
WIRE 16 -1 (2675 2250)(2575 2250);
WIRE 16 -1 (2850 3350)(2575 3350);
WIRE 16 -1 (2675 3400)(2575 3400);
WIRE 16 -1 (2850 2300)(2575 2300);
WIRE 16 -1 (2675 2350)(2575 2350);
WIRE 16 -1 (2850 3450)(2575 3450);
WIRE 16 -1 (2675 3500)(2575 3500);
WIRE 16 -1 (2850 2400)(2575 2400);
WIRE 16 -1 (2675 2450)(2575 2450);
WIRE 16 -1 (2850 3550)(2575 3550);
WIRE 16 -1 (2675 3600)(2575 3600);
WIRE 16 -1 (2850 2500)(2575 2500);
WIRE 16 -1 (2675 2550)(2575 2550);
WIRE 16 -1 (2850 3650)(2575 3650);
WIRE 16 -1 (2675 3700)(2575 3700);
WIRE 16 -1 (2850 2600)(2575 2600);
WIRE 16 -1 (2675 2650)(2575 2650);
WIRE 16 -1 (2850 3750)(2575 3750);
WIRE 16 -1 (2675 3800)(2575 3800);
WIRE 16 -1 (2850 2700)(2575 2700);
WIRE 16 -1 (2675 2750)(2575 2750);
WIRE 16 -1 (2850 3850)(2575 3850);
WIRE 16 -1 (2850 2800)(2575 2800);
WIRE 16 -1 (2675 2850)(2575 2850);
WIRE 16 -1 (2675 4000)(2575 4000);
WIRE 16 -1 (2850 2900)(2575 2900);
WIRE 16 -1 (2850 4050)(2575 4050);
WIRE 16 -1 (2675 4100)(2575 4100);
WIRE 16 -1 (2850 4150)(2575 4150);
WIRE 16 -1 (2675 4200)(2575 4200);
WIRE 16 -1 (2850 3100)(2575 3100);
WIRE 16 -1 (2675 3150)(2575 3150);
WIRE 16 -1 (2725 550)(2725 425);
WIRE 16 -1 (3350 550)(2725 550);
WIRE 16 -1 (3350 425)(3350 550);
WIRE 16 -1 (2725 75)(2725 225);
WIRE 16 -1 (3350 75)(2725 75);
WIRE 16 -1 (3350 75)(3350 225);
WIRE 16 -1 (4600 4050)(4350 4050);
WIRE 16 -1 (4350 4000)(4350 4050);
WIRE 16 -1 (4350 4000)(4600 4000);
WIRE 16 -1 (4350 3950)(4350 4000);
WIRE 16 -1 (4600 3950)(4350 3950);
WIRE 16 -1 (4350 3900)(4350 3950);
WIRE 16 -1 (4350 3900)(4600 3900);
WIRE 16 -1 (4350 3850)(4350 3900);
WIRE 16 -1 (4350 3850)(4600 3850);
WIRE 16 -1 (4350 3800)(4350 3850);
WIRE 16 -1 (4350 3800)(4600 3800);
WIRE 16 -1 (4350 3750)(4350 3800);
WIRE 16 -1 (4350 3750)(4600 3750);
WIRE 16 -1 (4350 3700)(4350 3750);
WIRE 16 -1 (4350 3700)(4600 3700);
WIRE 16 -1 (4350 3650)(4350 3700);
WIRE 16 -1 (4350 3650)(4600 3650);
WIRE 16 -1 (4350 3600)(4350 3650);
WIRE 16 -1 (4350 3600)(4600 3600);
WIRE 16 -1 (4350 3550)(4600 3550);
WIRE 16 -1 (4350 3550)(4350 3600);
WIRE 16 -1 (4350 3500)(4350 3550);
WIRE 16 -1 (4350 3500)(4600 3500);
WIRE 16 -1 (4350 3450)(4350 3500);
WIRE 16 -1 (4600 3450)(4350 3450);
WIRE 16 -1 (4350 3400)(4350 3450);
WIRE 16 -1 (4350 3400)(4600 3400);
WIRE 16 -1 (4350 3350)(4350 3400);
WIRE 16 -1 (4350 3350)(4600 3350);
WIRE 16 -1 (4350 3300)(4350 3350);
WIRE 16 -1 (4350 3300)(4600 3300);
WIRE 16 -1 (4350 3250)(4350 3300);
WIRE 16 -1 (4350 3250)(4600 3250);
WIRE 16 -1 (4350 3200)(4350 3250);
WIRE 16 -1 (4350 3200)(4600 3200);
WIRE 16 -1 (4350 3150)(4350 3200);
WIRE 16 -1 (4350 3150)(4600 3150);
WIRE 16 -1 (4350 3100)(4350 3150);
WIRE 16 -1 (4350 3100)(4600 3100);
WIRE 16 -1 (4350 3050)(4600 3050);
WIRE 16 -1 (4350 3050)(4350 3100);
WIRE 16 -1 (4350 3000)(4350 3050);
WIRE 16 -1 (4350 3000)(4600 3000);
WIRE 16 -1 (4350 2950)(4350 3000);
WIRE 16 -1 (4600 2950)(4350 2950);
WIRE 16 -1 (4350 2900)(4350 2950);
WIRE 16 -1 (4350 2900)(4600 2900);
WIRE 16 -1 (4350 2850)(4350 2900);
WIRE 16 -1 (4350 2850)(4600 2850);
WIRE 16 -1 (4350 2800)(4350 2850);
WIRE 16 -1 (4350 2800)(4600 2800);
WIRE 16 -1 (4350 2750)(4350 2800);
WIRE 16 -1 (4350 2750)(4600 2750);
WIRE 16 -1 (4350 2700)(4350 2750);
WIRE 16 -1 (4350 2700)(4600 2700);
WIRE 16 -1 (4350 2650)(4350 2700);
WIRE 16 -1 (4350 2650)(4600 2650);
WIRE 16 -1 (4350 2600)(4350 2650);
WIRE 16 -1 (4350 2600)(4600 2600);
WIRE 16 -1 (4350 2550)(4600 2550);
WIRE 16 -1 (4350 2550)(4350 2600);
WIRE 16 -1 (4350 2500)(4350 2550);
WIRE 16 -1 (4350 2500)(4600 2500);
WIRE 16 -1 (4350 2450)(4350 2500);
WIRE 16 -1 (4600 2450)(4350 2450);
WIRE 16 -1 (4350 2400)(4350 2450);
WIRE 16 -1 (4350 2400)(4600 2400);
WIRE 16 -1 (4350 2350)(4350 2400);
WIRE 16 -1 (4350 2350)(4600 2350);
WIRE 16 -1 (4350 2300)(4350 2350);
WIRE 16 -1 (4350 2300)(4600 2300);
WIRE 16 -1 (4350 2250)(4350 2300);
WIRE 16 -1 (4350 2250)(4600 2250);
WIRE 16 -1 (4350 2200)(4350 2250);
WIRE 16 -1 (4350 2200)(4600 2200);
WIRE 16 -1 (4350 2150)(4350 2200);
WIRE 16 -1 (4350 2150)(4600 2150);
WIRE 16 -1 (4350 2100)(4350 2150);
WIRE 16 -1 (4350 2100)(4600 2100);
WIRE 16 -1 (4350 2050)(4350 2100);
WIRE 16 -1 (4350 2050)(4600 2050);
WIRE 16 -1 (4350 2000)(4600 2000);
WIRE 16 -1 (4350 2000)(4350 2050);
WIRE 16 -1 (4350 1950)(4350 2000);
WIRE 16 -1 (4600 1950)(4350 1950);
WIRE 16 -1 (4350 1900)(4350 1950);
WIRE 16 -1 (4350 1900)(4600 1900);
WIRE 16 -1 (4350 1850)(4350 1900);
WIRE 16 -1 (4350 1850)(4600 1850);
WIRE 16 -1 (4350 1800)(4350 1850);
WIRE 16 -1 (4350 1800)(4600 1800);
WIRE 16 -1 (4350 1750)(4350 1800);
WIRE 16 -1 (4350 1750)(4600 1750);
WIRE 16 -1 (4350 1700)(4350 1750);
WIRE 16 -1 (4350 1700)(4600 1700);
WIRE 16 -1 (4350 1650)(4350 1700);
WIRE 16 -1 (4350 1650)(4600 1650);
WIRE 16 -1 (4350 1600)(4350 1650);
WIRE 16 -1 (4350 1600)(4600 1600);
WIRE 16 -1 (4350 1550)(4350 1600);
WIRE 16 -1 (4350 1550)(4600 1550);
WIRE 16 -1 (4350 1500)(4600 1500);
WIRE 16 -1 (4350 1500)(4350 1550);
WIRE 16 -1 (4350 1450)(4350 1500);
WIRE 16 -1 (4600 1450)(4350 1450);
WIRE 16 -1 (4350 1400)(4350 1450);
WIRE 16 -1 (4350 1400)(4600 1400);
WIRE 16 -1 (4350 1350)(4350 1400);
WIRE 16 -1 (4350 1350)(4600 1350);
WIRE 16 -1 (4350 1300)(4350 1350);
WIRE 16 -1 (4350 1300)(4600 1300);
WIRE 16 -1 (4350 1250)(4350 1300);
WIRE 16 -1 (4350 1250)(4600 1250);
WIRE 16 -1 (4350 1200)(4350 1250);
WIRE 16 -1 (4350 1200)(4600 1200);
WIRE 16 -1 (4350 1150)(4350 1200);
WIRE 16 -1 (4350 1150)(4600 1150);
WIRE 16 -1 (4350 1100)(4350 1150);
WIRE 16 -1 (4350 1100)(4600 1100);
WIRE 16 -1 (4350 1050)(4350 1100);
WIRE 16 -1 (4350 1050)(4600 1050);
WIRE 16 -1 (4350 1000)(4600 1000);
WIRE 16 -1 (4350 1000)(4350 1050);
WIRE 16 -1 (4350 950)(4350 1000);
WIRE 16 -1 (4350 950)(4600 950);
WIRE 16 -1 (4600 4100)(4350 4100);
WIRE 16 -1 (4350 4150)(4350 4100);
WIRE 16 -1 (4350 4150)(4600 4150);
WIRE 16 -1 (4350 4200)(4350 4150);
WIRE 16 -1 (4600 4200)(4350 4200);
WIRE 16 -1 (5800 900)(6050 900);
WIRE 16 -1 (5800 950)(6050 950);
WIRE 16 -1 (6050 950)(6050 900);
WIRE 16 -1 (6050 1050)(6050 950);
WIRE 16 -1 (5800 1050)(6050 1050);
WIRE 16 -1 (5800 1100)(6050 1100);
WIRE 16 -1 (6050 1100)(6050 1050);
WIRE 16 -1 (5800 1150)(6050 1150);
WIRE 16 -1 (6050 1100)(6050 1150);
WIRE 16 -1 (5800 1200)(6050 1200);
WIRE 16 -1 (6050 1200)(6050 1150);
WIRE 16 -1 (5800 1250)(6050 1250);
WIRE 16 -1 (6050 1250)(6050 1200);
WIRE 16 -1 (5800 1300)(6050 1300);
WIRE 16 -1 (6050 1300)(6050 1250);
WIRE 16 -1 (5800 1350)(6050 1350);
WIRE 16 -1 (6050 1350)(6050 1300);
WIRE 16 -1 (5800 1400)(6050 1400);
WIRE 16 -1 (6050 1400)(6050 1350);
WIRE 16 -1 (5800 1450)(6050 1450);
WIRE 16 -1 (6050 1450)(6050 1400);
WIRE 16 -1 (6050 1500)(5800 1500);
WIRE 16 -1 (6050 1500)(6050 1450);
WIRE 16 -1 (6050 1550)(6050 1500);
WIRE 16 -1 (6050 1550)(5800 1550);
WIRE 16 -1 (6050 1600)(5800 1600);
WIRE 16 -1 (6050 1600)(6050 1550);
WIRE 16 -1 (5800 1650)(6050 1650);
WIRE 16 -1 (6050 1600)(6050 1650);
WIRE 16 -1 (6050 1700)(5800 1700);
WIRE 16 -1 (6050 1650)(6050 1700);
WIRE 16 -1 (6050 1750)(5800 1750);
WIRE 16 -1 (6050 1750)(6050 1700);
WIRE 16 -1 (6050 1800)(5800 1800);
WIRE 16 -1 (6050 1800)(6050 1750);
WIRE 16 -1 (6050 1850)(5800 1850);
WIRE 16 -1 (6050 1850)(6050 1800);
WIRE 16 -1 (5800 1900)(6050 1900);
WIRE 16 -1 (6050 1900)(6050 1850);
WIRE 16 -1 (5800 1950)(6050 1950);
WIRE 16 -1 (6050 1950)(6050 1900);
WIRE 16 -1 (5800 2000)(6050 2000);
WIRE 16 -1 (6050 1950)(6050 2000);
WIRE 16 -1 (6050 2050)(6050 2000);
WIRE 16 -1 (5800 2050)(6050 2050);
WIRE 16 -1 (5800 2100)(6050 2100);
WIRE 16 -1 (6050 2100)(6050 2050);
WIRE 16 -1 (5800 2150)(6050 2150);
WIRE 16 -1 (6050 2150)(6050 2100);
WIRE 16 -1 (5800 2200)(6050 2200);
WIRE 16 -1 (6050 2200)(6050 2150);
WIRE 16 -1 (5800 2250)(6050 2250);
WIRE 16 -1 (6050 2250)(6050 2200);
WIRE 16 -1 (6050 2300)(5800 2300);
WIRE 16 -1 (6050 2300)(6050 2250);
WIRE 16 -1 (6050 2350)(5800 2350);
WIRE 16 -1 (6050 2350)(6050 2300);
WIRE 16 -1 (5800 2400)(6050 2400);
WIRE 16 -1 (6050 2400)(6050 2350);
WIRE 16 -1 (5800 2450)(6050 2450);
WIRE 16 -1 (6050 2450)(6050 2400);
WIRE 16 -1 (5800 2500)(6050 2500);
WIRE 16 -1 (6050 2450)(6050 2500);
WIRE 16 -1 (5800 2550)(6050 2550);
WIRE 16 -1 (6050 2550)(6050 2500);
WIRE 16 -1 (6050 2600)(6050 2550);
WIRE 16 -1 (5800 2600)(6050 2600);
WIRE 16 -1 (5800 2650)(6050 2650);
WIRE 16 -1 (6050 2650)(6050 2600);
WIRE 16 -1 (5800 2700)(6050 2700);
WIRE 16 -1 (6050 2700)(6050 2650);
WIRE 16 -1 (5800 2750)(6050 2750);
WIRE 16 -1 (6050 2750)(6050 2700);
WIRE 16 -1 (6050 2800)(5800 2800);
WIRE 16 -1 (6050 2800)(6050 2750);
WIRE 16 -1 (6050 2850)(5800 2850);
WIRE 16 -1 (6050 2850)(6050 2800);
WIRE 16 -1 (5800 2900)(6050 2900);
WIRE 16 -1 (6050 2900)(6050 2850);
WIRE 16 -1 (5800 2950)(6050 2950);
WIRE 16 -1 (6050 2950)(6050 2900);
WIRE 16 -1 (5800 3000)(6050 3000);
WIRE 16 -1 (6050 2950)(6050 3000);
WIRE 16 -1 (5800 3050)(6050 3050);
WIRE 16 -1 (6050 3050)(6050 3000);
WIRE 16 -1 (6050 3100)(6050 3050);
WIRE 16 -1 (5800 3100)(6050 3100);
WIRE 16 -1 (5800 3150)(6050 3150);
WIRE 16 -1 (6050 3150)(6050 3100);
WIRE 16 -1 (5800 3200)(6050 3200);
WIRE 16 -1 (6050 3200)(6050 3150);
WIRE 16 -1 (5800 3250)(6050 3250);
WIRE 16 -1 (6050 3250)(6050 3200);
WIRE 16 -1 (6050 3300)(5800 3300);
WIRE 16 -1 (6050 3300)(6050 3250);
WIRE 16 -1 (6050 3350)(5800 3350);
WIRE 16 -1 (6050 3350)(6050 3300);
WIRE 16 -1 (5800 3400)(6050 3400);
WIRE 16 -1 (6050 3400)(6050 3350);
WIRE 16 -1 (5800 3450)(6050 3450);
WIRE 16 -1 (6050 3450)(6050 3400);
WIRE 16 -1 (5800 3500)(6050 3500);
WIRE 16 -1 (6050 3450)(6050 3500);
WIRE 16 -1 (5800 3550)(6050 3550);
WIRE 16 -1 (6050 3550)(6050 3500);
WIRE 16 -1 (6050 3600)(6050 3550);
WIRE 16 -1 (5800 3600)(6050 3600);
WIRE 16 -1 (5800 3650)(6050 3650);
WIRE 16 -1 (6050 3650)(6050 3600);
WIRE 16 -1 (5800 3700)(6050 3700);
WIRE 16 -1 (6050 3700)(6050 3650);
WIRE 16 -1 (5800 3750)(6050 3750);
WIRE 16 -1 (6050 3750)(6050 3700);
WIRE 16 -1 (5800 3800)(6050 3800);
WIRE 16 -1 (6050 3800)(6050 3750);
WIRE 16 -1 (5800 3850)(6050 3850);
WIRE 16 -1 (6050 3850)(6050 3800);
WIRE 16 -1 (5800 3900)(6050 3900);
WIRE 16 -1 (6050 3900)(6050 3850);
WIRE 16 -1 (5800 3950)(6050 3950);
WIRE 16 -1 (6050 3950)(6050 3900);
WIRE 16 -1 (5800 4000)(6050 4000);
WIRE 16 -1 (6050 4000)(6050 3950);
WIRE 16 -1 (5800 4050)(6050 4050);
WIRE 16 -1 (6050 4050)(6050 4000);
WIRE 16 -1 (6050 4100)(6050 4050);
WIRE 16 -1 (5800 4100)(6050 4100);
WIRE 16 -1 (5800 4150)(6050 4150);
WIRE 16 -1 (6050 4150)(6050 4100);
WIRE 16 -1 (6050 4200)(6050 4150);
WIRE 16 -1 (5800 4200)(6050 4200);
DOT 1 (2725 550);
DOT 1 (3350 75);
DOT 1 (4350 3900);
DOT 1 (4350 2750);
DOT 1 (4350 2050);
DOT 1 (4350 2350);
DOT 1 (4350 950);
DOT 1 (4350 1000);
DOT 1 (4350 1150);
DOT 1 (4350 1100);
DOT 1 (4350 1050);
DOT 1 (4350 1250);
DOT 1 (4350 1200);
DOT 1 (4350 1300);
DOT 1 (4350 1400);
DOT 1 (4350 1350);
DOT 1 (4350 1450);
DOT 1 (4350 1500);
DOT 1 (4350 1550);
DOT 1 (4350 1600);
DOT 1 (4350 1650);
DOT 1 (4350 1700);
DOT 1 (4350 1750);
DOT 1 (4350 1800);
DOT 1 (4350 1850);
DOT 1 (4350 1900);
DOT 1 (4350 1950);
DOT 1 (4350 2000);
DOT 1 (6050 1050);
DOT 1 (6050 1100);
DOT 1 (6050 1150);
DOT 1 (6050 1200);
DOT 1 (6050 1250);
DOT 1 (6050 1300);
DOT 1 (6050 1350);
DOT 1 (6050 1400);
DOT 1 (6050 1500);
DOT 1 (6050 1450);
DOT 1 (6050 1550);
DOT 1 (6050 1600);
DOT 1 (6050 1650);
DOT 1 (6050 1700);
DOT 1 (6050 1750);
DOT 1 (6050 1800);
DOT 1 (6050 1850);
DOT 1 (6050 1900);
DOT 1 (6050 1950);
DOT 1 (6050 2000);
DOT 1 (6050 2050);
DOT 1 (4350 2150);
DOT 1 (4350 2100);
DOT 1 (4350 2200);
DOT 1 (4350 2300);
DOT 1 (4350 2250);
DOT 1 (4350 2400);
DOT 1 (4350 2450);
DOT 1 (4350 2550);
DOT 1 (4350 2500);
DOT 1 (4350 2650);
DOT 1 (4350 2600);
DOT 1 (4350 2700);
DOT 1 (4350 2800);
DOT 1 (4350 2850);
DOT 1 (4350 2900);
DOT 1 (4350 2950);
DOT 1 (4350 3000);
DOT 1 (4350 3050);
DOT 1 (4350 3150);
DOT 1 (4350 3100);
DOT 1 (4350 3200);
DOT 1 (4350 3300);
DOT 1 (4350 3250);
DOT 1 (4350 3450);
DOT 1 (4350 3400);
DOT 1 (4350 3550);
DOT 1 (4350 3500);
DOT 1 (4350 3650);
DOT 1 (4350 3600);
DOT 1 (4350 3750);
DOT 1 (4350 3800);
DOT 1 (4350 3850);
DOT 1 (4350 3950);
DOT 1 (4350 4000);
DOT 1 (6050 2100);
DOT 1 (6050 2150);
DOT 1 (6050 2200);
DOT 1 (6050 2250);
DOT 1 (6050 2300);
DOT 1 (6050 2350);
DOT 1 (6050 2400);
DOT 1 (6050 2450);
DOT 1 (6050 2500);
DOT 1 (6050 2550);
DOT 1 (6050 2650);
DOT 1 (6050 2600);
DOT 1 (6050 2700);
DOT 1 (6050 2750);
DOT 1 (6050 2800);
DOT 1 (6050 2850);
DOT 1 (6050 2900);
DOT 1 (6050 2950);
DOT 1 (6050 3000);
DOT 1 (6050 3050);
DOT 1 (6050 3100);
DOT 1 (6050 3200);
DOT 1 (6050 3150);
DOT 1 (6050 3250);
DOT 1 (6050 3300);
DOT 1 (6050 3350);
DOT 1 (6050 3400);
DOT 1 (6050 3450);
DOT 1 (6050 3500);
DOT 1 (6050 3550);
DOT 1 (6050 3600);
DOT 1 (6050 3650);
DOT 1 (6050 3700);
DOT 1 (6050 3750);
DOT 1 (6050 3800);
DOT 1 (6050 3850);
DOT 1 (6050 3900);
DOT 1 (6050 3950);
DOT 1 (6050 4000);
DOT 1 (6050 4050);
DOT 1 (6050 4100);
DOT 1 (4350 4150);
DOT 1 (6050 4150);
DOT 1 (4350 4200);
DOT 1 (4350 3350);
DOT 1 (6050 950);
DOT 1 (6050 900);
DOT 1 (6050 850);
DOT 1 (4350 3700);
FORCENOTE
20210728 MODIFY FOR GT
(-2925 4850) 0;
DISPLAY LEFT (-2925 4850);
DISPLAY 2.510638 (-2925 4850);
PAINT PINK (-2925 4850);
QUIT
